(kicad_sch
	(version 20250114)
	(generator "eeschema")
	(generator_version "9.0")
	(paper "A3")
	(title_block
		(title "LPDDR5 Testbed")
		(date "2023-12-19")
		(rev "1.0.0")
	)
	(bus_alias "LPDDR5"
		(members "CK_N" "CK_P" "CA[0..6]" "DQ[0..15]" "DMI[0..1]" "CS[0..1]" "WCK1_N"
			"WCK1_P" "WCK0_N" "WCK0_P" "RDQS0_N" "RDQS0_P" "RDQS1_N" "RDQS1_P"
		)
	)
	(text "SODIMM Connector"
		(exclude_from_sim no)
		(at 22.86 22.225 0)
		(effects
			(font
				(size 2.4892 2.4892)
				(thickness 0.4978)
				(bold yes)
			)
			(justify left bottom)
		)
	)
	(junction
		(at 160.02 232.41)
		(diameter 0)
		(color 0 0 0 0)
	)
	(junction
		(at 167.64 30.48)
		(diameter 0)
		(color 0 0 0 0)
	)
	(junction
		(at 307.34 91.44)
		(diameter 0)
		(color 0 0 0 0)
	)
	(junction
		(at 210.82 40.64)
		(diameter 0)
		(color 0 0 0 0)
	)
	(junction
		(at 248.285 65.405)
		(diameter 0)
		(color 0 0 0 0)
	)
	(junction
		(at 161.29 40.64)
		(diameter 0)
		(color 0 0 0 0)
	)
	(junction
		(at 154.94 91.44)
		(diameter 0)
		(color 0 0 0 0)
	)
	(junction
		(at 213.995 43.18)
		(diameter 0)
		(color 0 0 0 0)
	)
	(junction
		(at 161.29 30.48)
		(diameter 0)
		(color 0 0 0 0)
	)
	(junction
		(at 312.42 232.41)
		(diameter 0)
		(color 0 0 0 0)
	)
	(junction
		(at 248.285 59.055)
		(diameter 0)
		(color 0 0 0 0)
	)
	(junction
		(at 161.29 50.8)
		(diameter 0)
		(color 0 0 0 0)
	)
	(no_connect
		(at 85.09 195.58)
	)
	(no_connect
		(at 237.49 198.12)
	)
	(no_connect
		(at 85.09 167.64)
	)
	(no_connect
		(at 170.18 43.18)
	)
	(no_connect
		(at 237.49 193.04)
	)
	(no_connect
		(at 237.49 175.26)
	)
	(no_connect
		(at 85.09 139.7)
	)
	(no_connect
		(at 85.09 175.26)
	)
	(no_connect
		(at 195.58 38.1)
	)
	(no_connect
		(at 85.09 162.56)
	)
	(no_connect
		(at 85.09 170.18)
	)
	(no_connect
		(at 237.49 139.7)
	)
	(no_connect
		(at 237.49 137.16)
	)
	(no_connect
		(at 85.09 172.72)
	)
	(no_connect
		(at 237.49 185.42)
	)
	(no_connect
		(at 237.49 162.56)
	)
	(no_connect
		(at 85.09 190.5)
	)
	(no_connect
		(at 195.58 50.8)
	)
	(no_connect
		(at 85.09 193.04)
	)
	(no_connect
		(at 237.49 170.18)
	)
	(no_connect
		(at 85.09 185.42)
	)
	(no_connect
		(at 85.09 165.1)
	)
	(no_connect
		(at 85.09 198.12)
	)
	(no_connect
		(at 237.49 190.5)
	)
	(no_connect
		(at 85.09 182.88)
	)
	(no_connect
		(at 170.18 48.26)
	)
	(no_connect
		(at 237.49 182.88)
	)
	(no_connect
		(at 237.49 165.1)
	)
	(no_connect
		(at 85.09 137.16)
	)
	(no_connect
		(at 237.49 195.58)
	)
	(no_connect
		(at 170.18 45.72)
	)
	(no_connect
		(at 237.49 167.64)
	)
	(no_connect
		(at 237.49 172.72)
	)
	(bus_entry
		(at 203.2 156.21)
		(size 1.27 1.27)
		(stroke
			(width 0)
			(type default)
		)
	)
	(bus_entry
		(at 158.75 213.36)
		(size 1.27 1.27)
		(stroke
			(width 0)
			(type default)
		)
	)
	(bus_entry
		(at 201.295 119.38)
		(size -1.27 1.27)
		(stroke
			(width 0)
			(type default)
		)
	)
	(bus_entry
		(at 307.34 219.71)
		(size -1.27 1.27)
		(stroke
			(width 0)
			(type default)
		)
	)
	(bus_entry
		(at 311.15 129.54)
		(size 1.27 1.27)
		(stroke
			(width 0)
			(type default)
		)
	)
	(bus_entry
		(at 307.34 153.67)
		(size -1.27 1.27)
		(stroke
			(width 0)
			(type default)
		)
	)
	(bus_entry
		(at 154.94 120.65)
		(size -1.27 1.27)
		(stroke
			(width 0)
			(type default)
		)
	)
	(bus_entry
		(at 50.8 128.27)
		(size 1.27 1.27)
		(stroke
			(width 0)
			(type default)
		)
	)
	(bus_entry
		(at 203.2 153.67)
		(size 1.27 1.27)
		(stroke
			(width 0)
			(type default)
		)
	)
	(bus_entry
		(at 46.99 116.84)
		(size -1.27 1.27)
		(stroke
			(width 0)
			(type default)
		)
	)
	(bus_entry
		(at 154.94 110.49)
		(size -1.27 1.27)
		(stroke
			(width 0)
			(type default)
		)
	)
	(bus_entry
		(at 154.94 171.45)
		(size -1.27 1.27)
		(stroke
			(width 0)
			(type default)
		)
	)
	(bus_entry
		(at 154.94 102.87)
		(size -1.27 1.27)
		(stroke
			(width 0)
			(type default)
		)
	)
	(bus_entry
		(at 158.75 198.12)
		(size 1.27 1.27)
		(stroke
			(width 0)
			(type default)
		)
	)
	(bus_entry
		(at 158.75 218.44)
		(size 1.27 1.27)
		(stroke
			(width 0)
			(type default)
		)
	)
	(bus_entry
		(at 158.75 160.02)
		(size 1.27 1.27)
		(stroke
			(width 0)
			(type default)
		)
	)
	(bus_entry
		(at 154.94 179.07)
		(size -1.27 1.27)
		(stroke
			(width 0)
			(type default)
		)
	)
	(bus_entry
		(at 158.75 210.82)
		(size 1.27 1.27)
		(stroke
			(width 0)
			(type default)
		)
	)
	(bus_entry
		(at 238.125 43.18)
		(size 1.27 1.27)
		(stroke
			(width 0)
			(type default)
		)
	)
	(bus_entry
		(at 307.34 214.63)
		(size -1.27 1.27)
		(stroke
			(width 0)
			(type default)
		)
	)
	(bus_entry
		(at 158.75 152.4)
		(size 1.27 1.27)
		(stroke
			(width 0)
			(type default)
		)
	)
	(bus_entry
		(at 307.34 158.75)
		(size -1.27 1.27)
		(stroke
			(width 0)
			(type default)
		)
	)
	(bus_entry
		(at 154.94 128.27)
		(size -1.27 1.27)
		(stroke
			(width 0)
			(type default)
		)
	)
	(bus_entry
		(at 158.75 205.74)
		(size 1.27 1.27)
		(stroke
			(width 0)
			(type default)
		)
	)
	(bus_entry
		(at 158.75 203.2)
		(size 1.27 1.27)
		(stroke
			(width 0)
			(type default)
		)
	)
	(bus_entry
		(at 154.94 113.03)
		(size -1.27 1.27)
		(stroke
			(width 0)
			(type default)
		)
	)
	(bus_entry
		(at 311.15 177.8)
		(size 1.27 1.27)
		(stroke
			(width 0)
			(type default)
		)
	)
	(bus_entry
		(at 307.34 146.05)
		(size -1.27 1.27)
		(stroke
			(width 0)
			(type default)
		)
	)
	(bus_entry
		(at 238.125 40.64)
		(size 1.27 1.27)
		(stroke
			(width 0)
			(type default)
		)
	)
	(bus_entry
		(at 311.15 187.96)
		(size 1.27 1.27)
		(stroke
			(width 0)
			(type default)
		)
	)
	(bus_entry
		(at 158.75 154.94)
		(size 1.27 1.27)
		(stroke
			(width 0)
			(type default)
		)
	)
	(bus_entry
		(at 154.94 181.61)
		(size -1.27 1.27)
		(stroke
			(width 0)
			(type default)
		)
	)
	(bus_entry
		(at 307.34 201.93)
		(size -1.27 1.27)
		(stroke
			(width 0)
			(type default)
		)
	)
	(bus_entry
		(at 50.8 130.81)
		(size 1.27 1.27)
		(stroke
			(width 0)
			(type default)
		)
	)
	(bus_entry
		(at 307.34 148.59)
		(size -1.27 1.27)
		(stroke
			(width 0)
			(type default)
		)
	)
	(bus_entry
		(at 307.34 204.47)
		(size -1.27 1.27)
		(stroke
			(width 0)
			(type default)
		)
	)
	(bus_entry
		(at 158.75 137.16)
		(size 1.27 1.27)
		(stroke
			(width 0)
			(type default)
		)
	)
	(bus_entry
		(at 311.15 111.76)
		(size 1.27 1.27)
		(stroke
			(width 0)
			(type default)
		)
	)
	(bus_entry
		(at 154.94 125.73)
		(size -1.27 1.27)
		(stroke
			(width 0)
			(type default)
		)
	)
	(bus_entry
		(at 158.75 142.24)
		(size 1.27 1.27)
		(stroke
			(width 0)
			(type default)
		)
	)
	(bus_entry
		(at 50.8 151.13)
		(size 1.27 1.27)
		(stroke
			(width 0)
			(type default)
		)
	)
	(bus_entry
		(at 307.34 135.89)
		(size -1.27 1.27)
		(stroke
			(width 0)
			(type default)
		)
	)
	(bus_entry
		(at 154.94 176.53)
		(size -1.27 1.27)
		(stroke
			(width 0)
			(type default)
		)
	)
	(bus_entry
		(at 158.75 144.78)
		(size 1.27 1.27)
		(stroke
			(width 0)
			(type default)
		)
	)
	(bus_entry
		(at 311.15 182.88)
		(size 1.27 1.27)
		(stroke
			(width 0)
			(type default)
		)
	)
	(bus_entry
		(at 50.8 146.05)
		(size 1.27 1.27)
		(stroke
			(width 0)
			(type default)
		)
	)
	(bus_entry
		(at 158.75 208.28)
		(size 1.27 1.27)
		(stroke
			(width 0)
			(type default)
		)
	)
	(bus_entry
		(at 311.15 165.1)
		(size 1.27 1.27)
		(stroke
			(width 0)
			(type default)
		)
	)
	(bus_entry
		(at 158.75 195.58)
		(size 1.27 1.27)
		(stroke
			(width 0)
			(type default)
		)
	)
	(bus_entry
		(at 311.15 190.5)
		(size 1.27 1.27)
		(stroke
			(width 0)
			(type default)
		)
	)
	(bus_entry
		(at 154.94 184.15)
		(size -1.27 1.27)
		(stroke
			(width 0)
			(type default)
		)
	)
	(bus_entry
		(at 154.94 115.57)
		(size -1.27 1.27)
		(stroke
			(width 0)
			(type default)
		)
	)
	(bus_entry
		(at 154.94 166.37)
		(size -1.27 1.27)
		(stroke
			(width 0)
			(type default)
		)
	)
	(bus_entry
		(at 154.94 163.83)
		(size -1.27 1.27)
		(stroke
			(width 0)
			(type default)
		)
	)
	(bus_entry
		(at 307.34 194.31)
		(size -1.27 1.27)
		(stroke
			(width 0)
			(type default)
		)
	)
	(bus_entry
		(at 203.2 105.41)
		(size 1.27 1.27)
		(stroke
			(width 0)
			(type default)
		)
	)
	(bus_entry
		(at 307.34 209.55)
		(size -1.27 1.27)
		(stroke
			(width 0)
			(type default)
		)
	)
	(bus_entry
		(at 311.15 175.26)
		(size 1.27 1.27)
		(stroke
			(width 0)
			(type default)
		)
	)
	(bus_entry
		(at 311.15 104.14)
		(size 1.27 1.27)
		(stroke
			(width 0)
			(type default)
		)
	)
	(bus_entry
		(at 311.15 124.46)
		(size 1.27 1.27)
		(stroke
			(width 0)
			(type default)
		)
	)
	(bus_entry
		(at 311.15 119.38)
		(size 1.27 1.27)
		(stroke
			(width 0)
			(type default)
		)
	)
	(bus_entry
		(at 203.2 130.81)
		(size 1.27 1.27)
		(stroke
			(width 0)
			(type default)
		)
	)
	(bus_entry
		(at 311.15 172.72)
		(size 1.27 1.27)
		(stroke
			(width 0)
			(type default)
		)
	)
	(bus_entry
		(at 203.2 115.57)
		(size 1.27 1.27)
		(stroke
			(width 0)
			(type default)
		)
	)
	(bus_entry
		(at 311.15 116.84)
		(size 1.27 1.27)
		(stroke
			(width 0)
			(type default)
		)
	)
	(bus_entry
		(at 154.94 118.11)
		(size -1.27 1.27)
		(stroke
			(width 0)
			(type default)
		)
	)
	(bus_entry
		(at 307.34 140.97)
		(size -1.27 1.27)
		(stroke
			(width 0)
			(type default)
		)
	)
	(bus_entry
		(at 50.8 102.87)
		(size 1.27 1.27)
		(stroke
			(width 0)
			(type default)
		)
	)
	(bus_entry
		(at 154.94 189.23)
		(size -1.27 1.27)
		(stroke
			(width 0)
			(type default)
		)
	)
	(bus_entry
		(at 307.34 207.01)
		(size -1.27 1.27)
		(stroke
			(width 0)
			(type default)
		)
	)
	(bus_entry
		(at 203.2 128.27)
		(size 1.27 1.27)
		(stroke
			(width 0)
			(type default)
		)
	)
	(bus_entry
		(at 50.8 113.03)
		(size 1.27 1.27)
		(stroke
			(width 0)
			(type default)
		)
	)
	(bus_entry
		(at 50.8 148.59)
		(size 1.27 1.27)
		(stroke
			(width 0)
			(type default)
		)
	)
	(bus_entry
		(at 311.15 180.34)
		(size 1.27 1.27)
		(stroke
			(width 0)
			(type default)
		)
	)
	(bus_entry
		(at 158.75 215.9)
		(size 1.27 1.27)
		(stroke
			(width 0)
			(type default)
		)
	)
	(bus_entry
		(at 311.15 185.42)
		(size 1.27 1.27)
		(stroke
			(width 0)
			(type default)
		)
	)
	(bus_entry
		(at 307.34 217.17)
		(size -1.27 1.27)
		(stroke
			(width 0)
			(type default)
		)
	)
	(bus_entry
		(at 311.15 106.68)
		(size 1.27 1.27)
		(stroke
			(width 0)
			(type default)
		)
	)
	(bus_entry
		(at 307.34 143.51)
		(size -1.27 1.27)
		(stroke
			(width 0)
			(type default)
		)
	)
	(bus_entry
		(at 203.2 146.05)
		(size 1.27 1.27)
		(stroke
			(width 0)
			(type default)
		)
	)
	(bus_entry
		(at 307.34 196.85)
		(size -1.27 1.27)
		(stroke
			(width 0)
			(type default)
		)
	)
	(bus_entry
		(at 50.8 118.11)
		(size 1.27 1.27)
		(stroke
			(width 0)
			(type default)
		)
	)
	(bus_entry
		(at 154.94 186.69)
		(size -1.27 1.27)
		(stroke
			(width 0)
			(type default)
		)
	)
	(bus_entry
		(at 307.34 133.35)
		(size -1.27 1.27)
		(stroke
			(width 0)
			(type default)
		)
	)
	(bus_entry
		(at 203.2 143.51)
		(size 1.27 1.27)
		(stroke
			(width 0)
			(type default)
		)
	)
	(bus_entry
		(at 203.2 151.13)
		(size 1.27 1.27)
		(stroke
			(width 0)
			(type default)
		)
	)
	(bus_entry
		(at 50.8 105.41)
		(size 1.27 1.27)
		(stroke
			(width 0)
			(type default)
		)
	)
	(bus_entry
		(at 50.8 153.67)
		(size 1.27 1.27)
		(stroke
			(width 0)
			(type default)
		)
	)
	(bus_entry
		(at 307.34 212.09)
		(size -1.27 1.27)
		(stroke
			(width 0)
			(type default)
		)
	)
	(bus_entry
		(at 311.15 114.3)
		(size 1.27 1.27)
		(stroke
			(width 0)
			(type default)
		)
	)
	(bus_entry
		(at 311.15 121.92)
		(size 1.27 1.27)
		(stroke
			(width 0)
			(type default)
		)
	)
	(bus_entry
		(at 311.15 127)
		(size 1.27 1.27)
		(stroke
			(width 0)
			(type default)
		)
	)
	(bus_entry
		(at 311.15 167.64)
		(size 1.27 1.27)
		(stroke
			(width 0)
			(type default)
		)
	)
	(bus_entry
		(at 158.75 149.86)
		(size 1.27 1.27)
		(stroke
			(width 0)
			(type default)
		)
	)
	(bus_entry
		(at 203.2 148.59)
		(size 1.27 1.27)
		(stroke
			(width 0)
			(type default)
		)
	)
	(bus_entry
		(at 203.2 120.65)
		(size 1.27 1.27)
		(stroke
			(width 0)
			(type default)
		)
	)
	(bus_entry
		(at 154.94 123.19)
		(size -1.27 1.27)
		(stroke
			(width 0)
			(type default)
		)
	)
	(bus_entry
		(at 158.75 157.48)
		(size 1.27 1.27)
		(stroke
			(width 0)
			(type default)
		)
	)
	(bus_entry
		(at 46.99 121.92)
		(size -1.27 1.27)
		(stroke
			(width 0)
			(type default)
		)
	)
	(bus_entry
		(at 203.2 158.75)
		(size 1.27 1.27)
		(stroke
			(width 0)
			(type default)
		)
	)
	(bus_entry
		(at 307.34 151.13)
		(size -1.27 1.27)
		(stroke
			(width 0)
			(type default)
		)
	)
	(bus_entry
		(at 158.75 147.32)
		(size 1.27 1.27)
		(stroke
			(width 0)
			(type default)
		)
	)
	(bus_entry
		(at 201.295 114.3)
		(size -1.27 1.27)
		(stroke
			(width 0)
			(type default)
		)
	)
	(bus_entry
		(at 154.94 173.99)
		(size -1.27 1.27)
		(stroke
			(width 0)
			(type default)
		)
	)
	(bus_entry
		(at 158.75 134.62)
		(size 1.27 1.27)
		(stroke
			(width 0)
			(type default)
		)
	)
	(bus_entry
		(at 307.34 156.21)
		(size -1.27 1.27)
		(stroke
			(width 0)
			(type default)
		)
	)
	(bus_entry
		(at 50.8 156.21)
		(size 1.27 1.27)
		(stroke
			(width 0)
			(type default)
		)
	)
	(bus_entry
		(at 50.8 143.51)
		(size 1.27 1.27)
		(stroke
			(width 0)
			(type default)
		)
	)
	(bus_entry
		(at 203.2 102.87)
		(size 1.27 1.27)
		(stroke
			(width 0)
			(type default)
		)
	)
	(bus_entry
		(at 158.75 220.98)
		(size 1.27 1.27)
		(stroke
			(width 0)
			(type default)
		)
	)
	(bus_entry
		(at 50.8 158.75)
		(size 1.27 1.27)
		(stroke
			(width 0)
			(type default)
		)
	)
	(bus_entry
		(at 154.94 105.41)
		(size -1.27 1.27)
		(stroke
			(width 0)
			(type default)
		)
	)
	(bus
		(pts
			(xy 312.42 113.03) (xy 312.42 115.57)
		)
		(stroke
			(width 0)
			(type default)
		)
	)
	(bus
		(pts
			(xy 154.94 163.83) (xy 154.94 166.37)
		)
		(stroke
			(width 0)
			(type default)
		)
	)
	(wire
		(pts
			(xy 204.47 129.54) (xy 237.49 129.54)
		)
		(stroke
			(width 0)
			(type default)
		)
	)
	(bus
		(pts
			(xy 50.8 102.87) (xy 50.8 105.41)
		)
		(stroke
			(width 0)
			(type default)
		)
	)
	(bus
		(pts
			(xy 203.2 128.27) (xy 203.2 130.81)
		)
		(stroke
			(width 0)
			(type default)
		)
	)
	(wire
		(pts
			(xy 46.99 116.84) (xy 85.09 116.84)
		)
		(stroke
			(width 0)
			(type default)
		)
	)
	(bus
		(pts
			(xy 154.94 91.44) (xy 161.925 91.44)
		)
		(stroke
			(width 0)
			(type default)
		)
	)
	(wire
		(pts
			(xy 153.67 187.96) (xy 120.65 187.96)
		)
		(stroke
			(width 0)
			(type default)
		)
	)
	(wire
		(pts
			(xy 161.29 30.48) (xy 167.64 30.48)
		)
		(stroke
			(width 0)
			(type default)
		)
	)
	(wire
		(pts
			(xy 52.07 157.48) (xy 85.09 157.48)
		)
		(stroke
			(width 0)
			(type default)
		)
	)
	(wire
		(pts
			(xy 120.65 134.62) (xy 158.75 134.62)
		)
		(stroke
			(width 0)
			(type default)
		)
	)
	(bus
		(pts
			(xy 160.02 204.47) (xy 160.02 207.01)
		)
		(stroke
			(width 0)
			(type default)
		)
	)
	(bus
		(pts
			(xy 307.34 196.85) (xy 307.34 201.93)
		)
		(stroke
			(width 0)
			(type default)
		)
	)
	(wire
		(pts
			(xy 273.05 160.02) (xy 306.07 160.02)
		)
		(stroke
			(width 0)
			(type default)
		)
	)
	(wire
		(pts
			(xy 153.67 182.88) (xy 120.65 182.88)
		)
		(stroke
			(width 0)
			(type default)
		)
	)
	(wire
		(pts
			(xy 204.47 152.4) (xy 237.49 152.4)
		)
		(stroke
			(width 0)
			(type default)
		)
	)
	(wire
		(pts
			(xy 238.125 43.18) (xy 224.79 43.18)
		)
		(stroke
			(width 0)
			(type default)
		)
	)
	(bus
		(pts
			(xy 307.34 143.51) (xy 307.34 146.05)
		)
		(stroke
			(width 0)
			(type default)
		)
	)
	(bus
		(pts
			(xy 154.94 105.41) (xy 154.94 110.49)
		)
		(stroke
			(width 0)
			(type default)
		)
	)
	(bus
		(pts
			(xy 154.94 171.45) (xy 154.94 173.99)
		)
		(stroke
			(width 0)
			(type default)
		)
	)
	(wire
		(pts
			(xy 273.05 127) (xy 311.15 127)
		)
		(stroke
			(width 0)
			(type default)
		)
	)
	(bus
		(pts
			(xy 160.02 153.67) (xy 160.02 156.21)
		)
		(stroke
			(width 0)
			(type default)
		)
	)
	(wire
		(pts
			(xy 120.65 160.02) (xy 158.75 160.02)
		)
		(stroke
			(width 0)
			(type default)
		)
	)
	(wire
		(pts
			(xy 273.05 124.46) (xy 311.15 124.46)
		)
		(stroke
			(width 0)
			(type default)
		)
	)
	(bus
		(pts
			(xy 50.8 153.67) (xy 50.8 156.21)
		)
		(stroke
			(width 0)
			(type default)
		)
	)
	(wire
		(pts
			(xy 213.995 60.96) (xy 213.995 43.18)
		)
		(stroke
			(width 0)
			(type default)
		)
	)
	(bus
		(pts
			(xy 307.34 91.44) (xy 314.325 91.44)
		)
		(stroke
			(width 0)
			(type default)
		)
	)
	(bus
		(pts
			(xy 160.02 219.71) (xy 160.02 222.25)
		)
		(stroke
			(width 0)
			(type default)
		)
	)
	(wire
		(pts
			(xy 273.05 144.78) (xy 306.07 144.78)
		)
		(stroke
			(width 0)
			(type default)
		)
	)
	(bus
		(pts
			(xy 154.94 176.53) (xy 154.94 179.07)
		)
		(stroke
			(width 0)
			(type default)
		)
	)
	(wire
		(pts
			(xy 204.47 116.84) (xy 237.49 116.84)
		)
		(stroke
			(width 0)
			(type default)
		)
	)
	(bus
		(pts
			(xy 312.42 173.99) (xy 312.42 176.53)
		)
		(stroke
			(width 0)
			(type default)
		)
	)
	(wire
		(pts
			(xy 52.07 119.38) (xy 85.09 119.38)
		)
		(stroke
			(width 0)
			(type default)
		)
	)
	(bus
		(pts
			(xy 154.94 123.19) (xy 154.94 125.73)
		)
		(stroke
			(width 0)
			(type default)
		)
	)
	(bus
		(pts
			(xy 160.02 232.41) (xy 167.005 232.41)
		)
		(stroke
			(width 0)
			(type default)
		)
	)
	(wire
		(pts
			(xy 195.58 43.18) (xy 213.995 43.18)
		)
		(stroke
			(width 0)
			(type default)
		)
	)
	(wire
		(pts
			(xy 120.65 114.3) (xy 153.67 114.3)
		)
		(stroke
			(width 0)
			(type default)
		)
	)
	(wire
		(pts
			(xy 243.205 60.96) (xy 244.475 60.96)
		)
		(stroke
			(width 0)
			(type default)
		)
	)
	(bus
		(pts
			(xy 50.8 143.51) (xy 50.8 146.05)
		)
		(stroke
			(width 0)
			(type default)
		)
	)
	(bus
		(pts
			(xy 154.94 125.73) (xy 154.94 128.27)
		)
		(stroke
			(width 0)
			(type default)
		)
	)
	(bus
		(pts
			(xy 46.99 232.41) (xy 160.02 232.41)
		)
		(stroke
			(width 0)
			(type default)
		)
	)
	(bus
		(pts
			(xy 307.34 153.67) (xy 307.34 156.21)
		)
		(stroke
			(width 0)
			(type default)
		)
	)
	(wire
		(pts
			(xy 210.82 40.64) (xy 219.71 40.64)
		)
		(stroke
			(width 0)
			(type default)
		)
	)
	(wire
		(pts
			(xy 153.67 180.34) (xy 120.65 180.34)
		)
		(stroke
			(width 0)
			(type default)
		)
	)
	(wire
		(pts
			(xy 153.67 175.26) (xy 120.65 175.26)
		)
		(stroke
			(width 0)
			(type default)
		)
	)
	(bus
		(pts
			(xy 312.42 107.95) (xy 312.42 113.03)
		)
		(stroke
			(width 0)
			(type default)
		)
	)
	(wire
		(pts
			(xy 52.07 114.3) (xy 85.09 114.3)
		)
		(stroke
			(width 0)
			(type default)
		)
	)
	(bus
		(pts
			(xy 154.94 186.69) (xy 154.94 189.23)
		)
		(stroke
			(width 0)
			(type default)
		)
	)
	(wire
		(pts
			(xy 120.65 142.24) (xy 158.75 142.24)
		)
		(stroke
			(width 0)
			(type default)
		)
	)
	(bus
		(pts
			(xy 312.42 181.61) (xy 312.42 184.15)
		)
		(stroke
			(width 0)
			(type default)
		)
	)
	(wire
		(pts
			(xy 195.58 40.64) (xy 210.82 40.64)
		)
		(stroke
			(width 0)
			(type default)
		)
	)
	(wire
		(pts
			(xy 204.47 132.08) (xy 237.49 132.08)
		)
		(stroke
			(width 0)
			(type default)
		)
	)
	(wire
		(pts
			(xy 204.47 104.14) (xy 237.49 104.14)
		)
		(stroke
			(width 0)
			(type default)
		)
	)
	(bus
		(pts
			(xy 160.02 161.29) (xy 160.02 196.85)
		)
		(stroke
			(width 0)
			(type default)
		)
	)
	(bus
		(pts
			(xy 307.34 204.47) (xy 307.34 207.01)
		)
		(stroke
			(width 0)
			(type default)
		)
	)
	(bus
		(pts
			(xy 50.8 118.11) (xy 50.8 128.27)
		)
		(stroke
			(width 0)
			(type default)
		)
	)
	(bus
		(pts
			(xy 201.295 232.41) (xy 312.42 232.41)
		)
		(stroke
			(width 0)
			(type default)
		)
	)
	(wire
		(pts
			(xy 120.65 195.58) (xy 158.75 195.58)
		)
		(stroke
			(width 0)
			(type default)
		)
	)
	(bus
		(pts
			(xy 160.02 207.01) (xy 160.02 209.55)
		)
		(stroke
			(width 0)
			(type default)
		)
	)
	(wire
		(pts
			(xy 201.295 114.3) (xy 237.49 114.3)
		)
		(stroke
			(width 0)
			(type default)
		)
	)
	(bus
		(pts
			(xy 200.025 120.65) (xy 200.025 231.14)
		)
		(stroke
			(width 0)
			(type default)
		)
	)
	(bus
		(pts
			(xy 239.395 41.91) (xy 239.395 44.45)
		)
		(stroke
			(width 0)
			(type default)
		)
	)
	(wire
		(pts
			(xy 153.67 190.5) (xy 120.65 190.5)
		)
		(stroke
			(width 0)
			(type default)
		)
	)
	(wire
		(pts
			(xy 273.05 182.88) (xy 311.15 182.88)
		)
		(stroke
			(width 0)
			(type default)
		)
	)
	(wire
		(pts
			(xy 273.05 177.8) (xy 311.15 177.8)
		)
		(stroke
			(width 0)
			(type default)
		)
	)
	(wire
		(pts
			(xy 120.65 144.78) (xy 158.75 144.78)
		)
		(stroke
			(width 0)
			(type default)
		)
	)
	(bus
		(pts
			(xy 307.34 133.35) (xy 307.34 135.89)
		)
		(stroke
			(width 0)
			(type default)
		)
	)
	(wire
		(pts
			(xy 120.65 124.46) (xy 153.67 124.46)
		)
		(stroke
			(width 0)
			(type default)
		)
	)
	(wire
		(pts
			(xy 52.07 144.78) (xy 85.09 144.78)
		)
		(stroke
			(width 0)
			(type default)
		)
	)
	(wire
		(pts
			(xy 213.995 43.18) (xy 219.71 43.18)
		)
		(stroke
			(width 0)
			(type default)
		)
	)
	(bus
		(pts
			(xy 154.94 181.61) (xy 154.94 184.15)
		)
		(stroke
			(width 0)
			(type default)
		)
	)
	(wire
		(pts
			(xy 248.285 58.42) (xy 248.285 59.055)
		)
		(stroke
			(width 0)
			(type default)
		)
	)
	(bus
		(pts
			(xy 312.42 125.73) (xy 312.42 128.27)
		)
		(stroke
			(width 0)
			(type default)
		)
	)
	(wire
		(pts
			(xy 273.05 198.12) (xy 306.07 198.12)
		)
		(stroke
			(width 0)
			(type default)
		)
	)
	(wire
		(pts
			(xy 161.29 30.48) (xy 161.29 25.4)
		)
		(stroke
			(width 0)
			(type default)
		)
	)
	(wire
		(pts
			(xy 248.285 59.055) (xy 248.285 59.69)
		)
		(stroke
			(width 0)
			(type default)
		)
	)
	(wire
		(pts
			(xy 120.65 147.32) (xy 158.75 147.32)
		)
		(stroke
			(width 0)
			(type default)
		)
	)
	(wire
		(pts
			(xy 120.65 137.16) (xy 158.75 137.16)
		)
		(stroke
			(width 0)
			(type default)
		)
	)
	(wire
		(pts
			(xy 120.65 149.86) (xy 158.75 149.86)
		)
		(stroke
			(width 0)
			(type default)
		)
	)
	(bus
		(pts
			(xy 203.2 92.71) (xy 203.2 102.87)
		)
		(stroke
			(width 0)
			(type default)
		)
	)
	(wire
		(pts
			(xy 221.615 66.04) (xy 222.885 66.04)
		)
		(stroke
			(width 0)
			(type default)
		)
	)
	(wire
		(pts
			(xy 204.47 147.32) (xy 237.49 147.32)
		)
		(stroke
			(width 0)
			(type default)
		)
	)
	(wire
		(pts
			(xy 120.65 210.82) (xy 158.75 210.82)
		)
		(stroke
			(width 0)
			(type default)
		)
	)
	(bus
		(pts
			(xy 312.42 128.27) (xy 312.42 130.81)
		)
		(stroke
			(width 0)
			(type default)
		)
	)
	(wire
		(pts
			(xy 120.65 127) (xy 153.67 127)
		)
		(stroke
			(width 0)
			(type default)
		)
	)
	(wire
		(pts
			(xy 170.18 50.8) (xy 161.29 50.8)
		)
		(stroke
			(width 0)
			(type default)
		)
	)
	(wire
		(pts
			(xy 273.05 129.54) (xy 311.15 129.54)
		)
		(stroke
			(width 0)
			(type default)
		)
	)
	(bus
		(pts
			(xy 312.42 120.65) (xy 312.42 123.19)
		)
		(stroke
			(width 0)
			(type default)
		)
	)
	(wire
		(pts
			(xy 273.05 119.38) (xy 311.15 119.38)
		)
		(stroke
			(width 0)
			(type default)
		)
	)
	(bus
		(pts
			(xy 204.47 91.44) (xy 307.34 91.44)
		)
		(stroke
			(width 0)
			(type default)
		)
	)
	(bus
		(pts
			(xy 50.8 151.13) (xy 50.8 153.67)
		)
		(stroke
			(width 0)
			(type default)
		)
	)
	(bus
		(pts
			(xy 154.94 102.87) (xy 154.94 105.41)
		)
		(stroke
			(width 0)
			(type default)
		)
	)
	(bus
		(pts
			(xy 160.02 148.59) (xy 160.02 151.13)
		)
		(stroke
			(width 0)
			(type default)
		)
	)
	(bus
		(pts
			(xy 50.8 113.03) (xy 50.8 118.11)
		)
		(stroke
			(width 0)
			(type default)
		)
	)
	(bus
		(pts
			(xy 200.025 231.14) (xy 201.295 232.41)
		)
		(stroke
			(width 0)
			(type default)
		)
	)
	(wire
		(pts
			(xy 46.99 121.92) (xy 85.09 121.92)
		)
		(stroke
			(width 0)
			(type default)
		)
	)
	(bus
		(pts
			(xy 160.02 138.43) (xy 160.02 143.51)
		)
		(stroke
			(width 0)
			(type default)
		)
	)
	(wire
		(pts
			(xy 161.29 46.99) (xy 161.29 50.8)
		)
		(stroke
			(width 0)
			(type default)
		)
	)
	(wire
		(pts
			(xy 120.65 116.84) (xy 153.67 116.84)
		)
		(stroke
			(width 0)
			(type default)
		)
	)
	(wire
		(pts
			(xy 120.65 104.14) (xy 153.67 104.14)
		)
		(stroke
			(width 0)
			(type default)
		)
	)
	(wire
		(pts
			(xy 273.05 180.34) (xy 311.15 180.34)
		)
		(stroke
			(width 0)
			(type default)
		)
	)
	(wire
		(pts
			(xy 244.475 65.405) (xy 244.475 63.5)
		)
		(stroke
			(width 0)
			(type default)
		)
	)
	(wire
		(pts
			(xy 273.05 172.72) (xy 311.15 172.72)
		)
		(stroke
			(width 0)
			(type default)
		)
	)
	(bus
		(pts
			(xy 203.2 146.05) (xy 203.2 148.59)
		)
		(stroke
			(width 0)
			(type default)
		)
	)
	(wire
		(pts
			(xy 222.885 60.96) (xy 213.995 60.96)
		)
		(stroke
			(width 0)
			(type default)
		)
	)
	(wire
		(pts
			(xy 52.07 149.86) (xy 85.09 149.86)
		)
		(stroke
			(width 0)
			(type default)
		)
	)
	(wire
		(pts
			(xy 273.05 111.76) (xy 311.15 111.76)
		)
		(stroke
			(width 0)
			(type default)
		)
	)
	(wire
		(pts
			(xy 273.05 154.94) (xy 306.07 154.94)
		)
		(stroke
			(width 0)
			(type default)
		)
	)
	(bus
		(pts
			(xy 203.2 153.67) (xy 203.2 156.21)
		)
		(stroke
			(width 0)
			(type default)
		)
	)
	(bus
		(pts
			(xy 160.02 209.55) (xy 160.02 212.09)
		)
		(stroke
			(width 0)
			(type default)
		)
	)
	(bus
		(pts
			(xy 154.94 173.99) (xy 154.94 176.53)
		)
		(stroke
			(width 0)
			(type default)
		)
	)
	(bus
		(pts
			(xy 312.42 123.19) (xy 312.42 125.73)
		)
		(stroke
			(width 0)
			(type default)
		)
	)
	(wire
		(pts
			(xy 52.07 154.94) (xy 85.09 154.94)
		)
		(stroke
			(width 0)
			(type default)
		)
	)
	(bus
		(pts
			(xy 45.72 118.11) (xy 45.72 123.19)
		)
		(stroke
			(width 0)
			(type default)
		)
	)
	(bus
		(pts
			(xy 154.94 128.27) (xy 154.94 163.83)
		)
		(stroke
			(width 0)
			(type default)
		)
	)
	(bus
		(pts
			(xy 307.34 146.05) (xy 307.34 148.59)
		)
		(stroke
			(width 0)
			(type default)
		)
	)
	(bus
		(pts
			(xy 50.8 156.21) (xy 50.8 158.75)
		)
		(stroke
			(width 0)
			(type default)
		)
	)
	(wire
		(pts
			(xy 120.65 205.74) (xy 158.75 205.74)
		)
		(stroke
			(width 0)
			(type default)
		)
	)
	(wire
		(pts
			(xy 273.05 149.86) (xy 306.07 149.86)
		)
		(stroke
			(width 0)
			(type default)
		)
	)
	(wire
		(pts
			(xy 204.47 144.78) (xy 237.49 144.78)
		)
		(stroke
			(width 0)
			(type default)
		)
	)
	(wire
		(pts
			(xy 273.05 167.64) (xy 311.15 167.64)
		)
		(stroke
			(width 0)
			(type default)
		)
	)
	(bus
		(pts
			(xy 45.72 231.14) (xy 46.99 232.41)
		)
		(stroke
			(width 0)
			(type default)
		)
	)
	(bus
		(pts
			(xy 203.2 102.87) (xy 203.2 105.41)
		)
		(stroke
			(width 0)
			(type default)
		)
	)
	(wire
		(pts
			(xy 273.05 185.42) (xy 311.15 185.42)
		)
		(stroke
			(width 0)
			(type default)
		)
	)
	(bus
		(pts
			(xy 307.34 135.89) (xy 307.34 140.97)
		)
		(stroke
			(width 0)
			(type default)
		)
	)
	(wire
		(pts
			(xy 273.05 187.96) (xy 311.15 187.96)
		)
		(stroke
			(width 0)
			(type default)
		)
	)
	(bus
		(pts
			(xy 154.94 115.57) (xy 154.94 118.11)
		)
		(stroke
			(width 0)
			(type default)
		)
	)
	(bus
		(pts
			(xy 154.94 110.49) (xy 154.94 113.03)
		)
		(stroke
			(width 0)
			(type default)
		)
	)
	(wire
		(pts
			(xy 273.05 218.44) (xy 306.07 218.44)
		)
		(stroke
			(width 0)
			(type default)
		)
	)
	(bus
		(pts
			(xy 154.94 120.65) (xy 154.94 123.19)
		)
		(stroke
			(width 0)
			(type default)
		)
	)
	(wire
		(pts
			(xy 52.07 104.14) (xy 85.09 104.14)
		)
		(stroke
			(width 0)
			(type default)
		)
	)
	(bus
		(pts
			(xy 307.34 151.13) (xy 307.34 153.67)
		)
		(stroke
			(width 0)
			(type default)
		)
	)
	(wire
		(pts
			(xy 120.65 203.2) (xy 158.75 203.2)
		)
		(stroke
			(width 0)
			(type default)
		)
	)
	(bus
		(pts
			(xy 160.02 143.51) (xy 160.02 146.05)
		)
		(stroke
			(width 0)
			(type default)
		)
	)
	(bus
		(pts
			(xy 203.2 130.81) (xy 203.2 143.51)
		)
		(stroke
			(width 0)
			(type default)
		)
	)
	(bus
		(pts
			(xy 307.34 140.97) (xy 307.34 143.51)
		)
		(stroke
			(width 0)
			(type default)
		)
	)
	(wire
		(pts
			(xy 273.05 208.28) (xy 306.07 208.28)
		)
		(stroke
			(width 0)
			(type default)
		)
	)
	(wire
		(pts
			(xy 161.29 40.64) (xy 170.18 40.64)
		)
		(stroke
			(width 0)
			(type default)
		)
	)
	(bus
		(pts
			(xy 312.42 191.77) (xy 312.42 232.41)
		)
		(stroke
			(width 0)
			(type default)
		)
	)
	(bus
		(pts
			(xy 312.42 186.69) (xy 312.42 189.23)
		)
		(stroke
			(width 0)
			(type default)
		)
	)
	(bus
		(pts
			(xy 312.42 176.53) (xy 312.42 179.07)
		)
		(stroke
			(width 0)
			(type default)
		)
	)
	(bus
		(pts
			(xy 45.72 123.19) (xy 45.72 231.14)
		)
		(stroke
			(width 0)
			(type default)
		)
	)
	(wire
		(pts
			(xy 120.65 215.9) (xy 158.75 215.9)
		)
		(stroke
			(width 0)
			(type default)
		)
	)
	(bus
		(pts
			(xy 200.025 115.57) (xy 200.025 120.65)
		)
		(stroke
			(width 0)
			(type default)
		)
	)
	(wire
		(pts
			(xy 204.47 160.02) (xy 237.49 160.02)
		)
		(stroke
			(width 0)
			(type default)
		)
	)
	(wire
		(pts
			(xy 273.05 215.9) (xy 306.07 215.9)
		)
		(stroke
			(width 0)
			(type default)
		)
	)
	(bus
		(pts
			(xy 307.34 209.55) (xy 307.34 212.09)
		)
		(stroke
			(width 0)
			(type default)
		)
	)
	(wire
		(pts
			(xy 120.65 198.12) (xy 158.75 198.12)
		)
		(stroke
			(width 0)
			(type default)
		)
	)
	(wire
		(pts
			(xy 273.05 134.62) (xy 306.07 134.62)
		)
		(stroke
			(width 0)
			(type default)
		)
	)
	(bus
		(pts
			(xy 245.745 48.26) (xy 240.665 48.26)
		)
		(stroke
			(width 0)
			(type default)
		)
	)
	(wire
		(pts
			(xy 248.285 64.77) (xy 248.285 65.405)
		)
		(stroke
			(width 0)
			(type default)
		)
	)
	(wire
		(pts
			(xy 120.65 121.92) (xy 153.67 121.92)
		)
		(stroke
			(width 0)
			(type default)
		)
	)
	(wire
		(pts
			(xy 153.67 172.72) (xy 120.65 172.72)
		)
		(stroke
			(width 0)
			(type default)
		)
	)
	(bus
		(pts
			(xy 50.8 128.27) (xy 50.8 130.81)
		)
		(stroke
			(width 0)
			(type default)
		)
	)
	(wire
		(pts
			(xy 120.65 220.98) (xy 158.75 220.98)
		)
		(stroke
			(width 0)
			(type default)
		)
	)
	(bus
		(pts
			(xy 307.34 194.31) (xy 307.34 196.85)
		)
		(stroke
			(width 0)
			(type default)
		)
	)
	(wire
		(pts
			(xy 201.295 119.38) (xy 237.49 119.38)
		)
		(stroke
			(width 0)
			(type default)
		)
	)
	(bus
		(pts
			(xy 203.2 120.65) (xy 203.2 128.27)
		)
		(stroke
			(width 0)
			(type default)
		)
	)
	(bus
		(pts
			(xy 312.42 166.37) (xy 312.42 168.91)
		)
		(stroke
			(width 0)
			(type default)
		)
	)
	(wire
		(pts
			(xy 161.29 41.91) (xy 161.29 40.64)
		)
		(stroke
			(width 0)
			(type default)
		)
	)
	(bus
		(pts
			(xy 50.8 146.05) (xy 50.8 148.59)
		)
		(stroke
			(width 0)
			(type default)
		)
	)
	(wire
		(pts
			(xy 52.07 152.4) (xy 85.09 152.4)
		)
		(stroke
			(width 0)
			(type default)
		)
	)
	(wire
		(pts
			(xy 120.65 157.48) (xy 158.75 157.48)
		)
		(stroke
			(width 0)
			(type default)
		)
	)
	(wire
		(pts
			(xy 205.74 30.48) (xy 195.58 30.48)
		)
		(stroke
			(width 0)
			(type default)
		)
	)
	(bus
		(pts
			(xy 307.34 156.21) (xy 307.34 158.75)
		)
		(stroke
			(width 0)
			(type default)
		)
	)
	(wire
		(pts
			(xy 273.05 165.1) (xy 311.15 165.1)
		)
		(stroke
			(width 0)
			(type default)
		)
	)
	(bus
		(pts
			(xy 160.02 158.75) (xy 160.02 161.29)
		)
		(stroke
			(width 0)
			(type default)
		)
	)
	(wire
		(pts
			(xy 244.475 60.96) (xy 244.475 59.055)
		)
		(stroke
			(width 0)
			(type default)
		)
	)
	(wire
		(pts
			(xy 153.67 167.64) (xy 120.65 167.64)
		)
		(stroke
			(width 0)
			(type default)
		)
	)
	(bus
		(pts
			(xy 307.34 212.09) (xy 307.34 214.63)
		)
		(stroke
			(width 0)
			(type default)
		)
	)
	(bus
		(pts
			(xy 160.02 196.85) (xy 160.02 199.39)
		)
		(stroke
			(width 0)
			(type default)
		)
	)
	(wire
		(pts
			(xy 273.05 104.14) (xy 311.15 104.14)
		)
		(stroke
			(width 0)
			(type default)
		)
	)
	(bus
		(pts
			(xy 203.2 148.59) (xy 203.2 151.13)
		)
		(stroke
			(width 0)
			(type default)
		)
	)
	(wire
		(pts
			(xy 167.64 29.21) (xy 167.64 30.48)
		)
		(stroke
			(width 0)
			(type default)
		)
	)
	(wire
		(pts
			(xy 195.58 33.02) (xy 205.74 33.02)
		)
		(stroke
			(width 0)
			(type default)
		)
	)
	(bus
		(pts
			(xy 160.02 214.63) (xy 160.02 217.17)
		)
		(stroke
			(width 0)
			(type default)
		)
	)
	(wire
		(pts
			(xy 120.65 129.54) (xy 153.67 129.54)
		)
		(stroke
			(width 0)
			(type default)
		)
	)
	(bus
		(pts
			(xy 312.42 184.15) (xy 312.42 186.69)
		)
		(stroke
			(width 0)
			(type default)
		)
	)
	(bus
		(pts
			(xy 50.8 92.71) (xy 52.07 91.44)
		)
		(stroke
			(width 0)
			(type default)
		)
	)
	(wire
		(pts
			(xy 52.07 160.02) (xy 85.09 160.02)
		)
		(stroke
			(width 0)
			(type default)
		)
	)
	(wire
		(pts
			(xy 120.65 152.4) (xy 158.75 152.4)
		)
		(stroke
			(width 0)
			(type default)
		)
	)
	(bus
		(pts
			(xy 154.94 118.11) (xy 154.94 120.65)
		)
		(stroke
			(width 0)
			(type default)
		)
	)
	(bus
		(pts
			(xy 50.8 105.41) (xy 50.8 113.03)
		)
		(stroke
			(width 0)
			(type default)
		)
	)
	(wire
		(pts
			(xy 120.65 106.68) (xy 153.67 106.68)
		)
		(stroke
			(width 0)
			(type default)
		)
	)
	(bus
		(pts
			(xy 154.94 166.37) (xy 154.94 171.45)
		)
		(stroke
			(width 0)
			(type default)
		)
	)
	(wire
		(pts
			(xy 273.05 121.92) (xy 311.15 121.92)
		)
		(stroke
			(width 0)
			(type default)
		)
	)
	(wire
		(pts
			(xy 273.05 213.36) (xy 306.07 213.36)
		)
		(stroke
			(width 0)
			(type default)
		)
	)
	(bus
		(pts
			(xy 307.34 91.44) (xy 307.34 133.35)
		)
		(stroke
			(width 0)
			(type default)
		)
	)
	(wire
		(pts
			(xy 273.05 116.84) (xy 311.15 116.84)
		)
		(stroke
			(width 0)
			(type default)
		)
	)
	(wire
		(pts
			(xy 204.47 149.86) (xy 237.49 149.86)
		)
		(stroke
			(width 0)
			(type default)
		)
	)
	(bus
		(pts
			(xy 203.2 105.41) (xy 203.2 115.57)
		)
		(stroke
			(width 0)
			(type default)
		)
	)
	(wire
		(pts
			(xy 273.05 195.58) (xy 306.07 195.58)
		)
		(stroke
			(width 0)
			(type default)
		)
	)
	(wire
		(pts
			(xy 273.05 205.74) (xy 306.07 205.74)
		)
		(stroke
			(width 0)
			(type default)
		)
	)
	(wire
		(pts
			(xy 120.65 119.38) (xy 153.67 119.38)
		)
		(stroke
			(width 0)
			(type default)
		)
	)
	(wire
		(pts
			(xy 52.07 132.08) (xy 85.09 132.08)
		)
		(stroke
			(width 0)
			(type default)
		)
	)
	(bus
		(pts
			(xy 203.2 143.51) (xy 203.2 146.05)
		)
		(stroke
			(width 0)
			(type default)
		)
	)
	(wire
		(pts
			(xy 52.07 147.32) (xy 85.09 147.32)
		)
		(stroke
			(width 0)
			(type default)
		)
	)
	(wire
		(pts
			(xy 221.615 67.31) (xy 221.615 66.04)
		)
		(stroke
			(width 0)
			(type default)
		)
	)
	(bus
		(pts
			(xy 160.02 222.25) (xy 160.02 232.41)
		)
		(stroke
			(width 0)
			(type default)
		)
	)
	(bus
		(pts
			(xy 154.94 113.03) (xy 154.94 115.57)
		)
		(stroke
			(width 0)
			(type default)
		)
	)
	(bus
		(pts
			(xy 312.42 118.11) (xy 312.42 120.65)
		)
		(stroke
			(width 0)
			(type default)
		)
	)
	(wire
		(pts
			(xy 273.05 114.3) (xy 311.15 114.3)
		)
		(stroke
			(width 0)
			(type default)
		)
	)
	(wire
		(pts
			(xy 204.47 106.68) (xy 237.49 106.68)
		)
		(stroke
			(width 0)
			(type default)
		)
	)
	(bus
		(pts
			(xy 203.2 151.13) (xy 203.2 153.67)
		)
		(stroke
			(width 0)
			(type default)
		)
	)
	(bus
		(pts
			(xy 154.94 179.07) (xy 154.94 181.61)
		)
		(stroke
			(width 0)
			(type default)
		)
	)
	(bus
		(pts
			(xy 312.42 168.91) (xy 312.42 173.99)
		)
		(stroke
			(width 0)
			(type default)
		)
	)
	(bus
		(pts
			(xy 50.8 92.71) (xy 50.8 102.87)
		)
		(stroke
			(width 0)
			(type default)
		)
	)
	(wire
		(pts
			(xy 204.47 154.94) (xy 237.49 154.94)
		)
		(stroke
			(width 0)
			(type default)
		)
	)
	(bus
		(pts
			(xy 160.02 156.21) (xy 160.02 158.75)
		)
		(stroke
			(width 0)
			(type default)
		)
	)
	(bus
		(pts
			(xy 239.395 44.45) (xy 239.395 46.99)
		)
		(stroke
			(width 0)
			(type default)
		)
	)
	(bus
		(pts
			(xy 203.2 156.21) (xy 203.2 158.75)
		)
		(stroke
			(width 0)
			(type default)
		)
	)
	(wire
		(pts
			(xy 273.05 210.82) (xy 306.07 210.82)
		)
		(stroke
			(width 0)
			(type default)
		)
	)
	(bus
		(pts
			(xy 160.02 146.05) (xy 160.02 148.59)
		)
		(stroke
			(width 0)
			(type default)
		)
	)
	(wire
		(pts
			(xy 273.05 220.98) (xy 306.07 220.98)
		)
		(stroke
			(width 0)
			(type default)
		)
	)
	(wire
		(pts
			(xy 244.475 59.055) (xy 248.285 59.055)
		)
		(stroke
			(width 0)
			(type default)
		)
	)
	(wire
		(pts
			(xy 120.65 154.94) (xy 158.75 154.94)
		)
		(stroke
			(width 0)
			(type default)
		)
	)
	(wire
		(pts
			(xy 244.475 63.5) (xy 243.205 63.5)
		)
		(stroke
			(width 0)
			(type default)
		)
	)
	(wire
		(pts
			(xy 52.07 129.54) (xy 85.09 129.54)
		)
		(stroke
			(width 0)
			(type default)
		)
	)
	(wire
		(pts
			(xy 204.47 121.92) (xy 237.49 121.92)
		)
		(stroke
			(width 0)
			(type default)
		)
	)
	(bus
		(pts
			(xy 312.42 115.57) (xy 312.42 118.11)
		)
		(stroke
			(width 0)
			(type default)
		)
	)
	(wire
		(pts
			(xy 273.05 147.32) (xy 306.07 147.32)
		)
		(stroke
			(width 0)
			(type default)
		)
	)
	(bus
		(pts
			(xy 160.02 217.17) (xy 160.02 219.71)
		)
		(stroke
			(width 0)
			(type default)
		)
	)
	(wire
		(pts
			(xy 273.05 142.24) (xy 306.07 142.24)
		)
		(stroke
			(width 0)
			(type default)
		)
	)
	(bus
		(pts
			(xy 154.94 91.44) (xy 154.94 102.87)
		)
		(stroke
			(width 0)
			(type default)
		)
	)
	(bus
		(pts
			(xy 52.07 91.44) (xy 154.94 91.44)
		)
		(stroke
			(width 0)
			(type default)
		)
	)
	(wire
		(pts
			(xy 204.47 157.48) (xy 237.49 157.48)
		)
		(stroke
			(width 0)
			(type default)
		)
	)
	(wire
		(pts
			(xy 120.65 111.76) (xy 153.67 111.76)
		)
		(stroke
			(width 0)
			(type default)
		)
	)
	(wire
		(pts
			(xy 52.07 106.68) (xy 85.09 106.68)
		)
		(stroke
			(width 0)
			(type default)
		)
	)
	(bus
		(pts
			(xy 307.34 207.01) (xy 307.34 209.55)
		)
		(stroke
			(width 0)
			(type default)
		)
	)
	(wire
		(pts
			(xy 120.65 208.28) (xy 158.75 208.28)
		)
		(stroke
			(width 0)
			(type default)
		)
	)
	(bus
		(pts
			(xy 50.8 130.81) (xy 50.8 143.51)
		)
		(stroke
			(width 0)
			(type default)
		)
	)
	(bus
		(pts
			(xy 307.34 217.17) (xy 307.34 219.71)
		)
		(stroke
			(width 0)
			(type default)
		)
	)
	(bus
		(pts
			(xy 312.42 179.07) (xy 312.42 181.61)
		)
		(stroke
			(width 0)
			(type default)
		)
	)
	(wire
		(pts
			(xy 167.64 30.48) (xy 170.18 30.48)
		)
		(stroke
			(width 0)
			(type default)
		)
	)
	(bus
		(pts
			(xy 203.2 92.71) (xy 204.47 91.44)
		)
		(stroke
			(width 0)
			(type default)
		)
	)
	(bus
		(pts
			(xy 312.42 232.41) (xy 319.405 232.41)
		)
		(stroke
			(width 0)
			(type default)
		)
	)
	(wire
		(pts
			(xy 273.05 190.5) (xy 311.15 190.5)
		)
		(stroke
			(width 0)
			(type default)
		)
	)
	(wire
		(pts
			(xy 153.67 177.8) (xy 120.65 177.8)
		)
		(stroke
			(width 0)
			(type default)
		)
	)
	(bus
		(pts
			(xy 50.8 148.59) (xy 50.8 151.13)
		)
		(stroke
			(width 0)
			(type default)
		)
	)
	(bus
		(pts
			(xy 307.34 148.59) (xy 307.34 151.13)
		)
		(stroke
			(width 0)
			(type default)
		)
	)
	(wire
		(pts
			(xy 161.29 50.8) (xy 161.29 52.07)
		)
		(stroke
			(width 0)
			(type default)
		)
	)
	(wire
		(pts
			(xy 273.05 106.68) (xy 311.15 106.68)
		)
		(stroke
			(width 0)
			(type default)
		)
	)
	(bus
		(pts
			(xy 312.42 105.41) (xy 312.42 107.95)
		)
		(stroke
			(width 0)
			(type default)
		)
	)
	(wire
		(pts
			(xy 238.125 40.64) (xy 224.79 40.64)
		)
		(stroke
			(width 0)
			(type default)
		)
	)
	(wire
		(pts
			(xy 273.05 203.2) (xy 306.07 203.2)
		)
		(stroke
			(width 0)
			(type default)
		)
	)
	(bus
		(pts
			(xy 160.02 135.89) (xy 160.02 138.43)
		)
		(stroke
			(width 0)
			(type default)
		)
	)
	(bus
		(pts
			(xy 307.34 214.63) (xy 307.34 217.17)
		)
		(stroke
			(width 0)
			(type default)
		)
	)
	(wire
		(pts
			(xy 195.58 48.26) (xy 197.485 48.26)
		)
		(stroke
			(width 0)
			(type default)
		)
	)
	(wire
		(pts
			(xy 273.05 152.4) (xy 306.07 152.4)
		)
		(stroke
			(width 0)
			(type default)
		)
	)
	(wire
		(pts
			(xy 120.65 213.36) (xy 158.75 213.36)
		)
		(stroke
			(width 0)
			(type default)
		)
	)
	(wire
		(pts
			(xy 273.05 157.48) (xy 306.07 157.48)
		)
		(stroke
			(width 0)
			(type default)
		)
	)
	(wire
		(pts
			(xy 244.475 65.405) (xy 248.285 65.405)
		)
		(stroke
			(width 0)
			(type default)
		)
	)
	(wire
		(pts
			(xy 222.885 63.5) (xy 210.82 63.5)
		)
		(stroke
			(width 0)
			(type default)
		)
	)
	(wire
		(pts
			(xy 161.29 39.37) (xy 161.29 40.64)
		)
		(stroke
			(width 0)
			(type default)
		)
	)
	(wire
		(pts
			(xy 273.05 175.26) (xy 311.15 175.26)
		)
		(stroke
			(width 0)
			(type default)
		)
	)
	(wire
		(pts
			(xy 120.65 218.44) (xy 158.75 218.44)
		)
		(stroke
			(width 0)
			(type default)
		)
	)
	(bus
		(pts
			(xy 154.94 184.15) (xy 154.94 186.69)
		)
		(stroke
			(width 0)
			(type default)
		)
	)
	(wire
		(pts
			(xy 161.29 30.48) (xy 161.29 34.29)
		)
		(stroke
			(width 0)
			(type default)
		)
	)
	(bus
		(pts
			(xy 203.2 115.57) (xy 203.2 120.65)
		)
		(stroke
			(width 0)
			(type default)
		)
	)
	(bus
		(pts
			(xy 307.34 158.75) (xy 307.34 194.31)
		)
		(stroke
			(width 0)
			(type default)
		)
	)
	(wire
		(pts
			(xy 210.82 63.5) (xy 210.82 40.64)
		)
		(stroke
			(width 0)
			(type default)
		)
	)
	(bus
		(pts
			(xy 312.42 189.23) (xy 312.42 191.77)
		)
		(stroke
			(width 0)
			(type default)
		)
	)
	(wire
		(pts
			(xy 273.05 137.16) (xy 306.07 137.16)
		)
		(stroke
			(width 0)
			(type default)
		)
	)
	(bus
		(pts
			(xy 239.395 46.99) (xy 240.665 48.26)
		)
		(stroke
			(width 0)
			(type default)
		)
	)
	(bus
		(pts
			(xy 312.42 130.81) (xy 312.42 166.37)
		)
		(stroke
			(width 0)
			(type default)
		)
	)
	(bus
		(pts
			(xy 307.34 201.93) (xy 307.34 204.47)
		)
		(stroke
			(width 0)
			(type default)
		)
	)
	(bus
		(pts
			(xy 160.02 199.39) (xy 160.02 204.47)
		)
		(stroke
			(width 0)
			(type default)
		)
	)
	(bus
		(pts
			(xy 160.02 212.09) (xy 160.02 214.63)
		)
		(stroke
			(width 0)
			(type default)
		)
	)
	(wire
		(pts
			(xy 248.285 65.405) (xy 248.285 66.04)
		)
		(stroke
			(width 0)
			(type default)
		)
	)
	(bus
		(pts
			(xy 160.02 151.13) (xy 160.02 153.67)
		)
		(stroke
			(width 0)
			(type default)
		)
	)
	(wire
		(pts
			(xy 153.67 185.42) (xy 120.65 185.42)
		)
		(stroke
			(width 0)
			(type default)
		)
	)
	(wire
		(pts
			(xy 153.67 165.1) (xy 120.65 165.1)
		)
		(stroke
			(width 0)
			(type default)
		)
	)
	(label "LPDDR5_IN_B.DQ3"
		(at 277.495 213.36 0)
		(effects
			(font
				(size 1.27 1.27)
			)
			(justify left bottom)
		)
	)
	(label "LPDDR5_IN_B.CK_P"
		(at 209.55 129.54 0)
		(effects
			(font
				(size 1.27 1.27)
			)
			(justify left bottom)
		)
	)
	(label "LPDDR5_IN_A.CA4"
		(at 57.15 154.94 0)
		(effects
			(font
				(size 1.27 1.27)
			)
			(justify left bottom)
		)
	)
	(label "LPDDR5_OUT_A.RDQS1_N"
		(at 127 137.16 0)
		(effects
			(font
				(size 1.27 1.27)
			)
			(justify left bottom)
		)
	)
	(label "LPDDR5_OUT_A.RDQS0_P"
		(at 127 195.58 0)
		(effects
			(font
				(size 1.27 1.27)
			)
			(justify left bottom)
		)
	)
	(label "LPDDR5_OUT_B.DQ3"
		(at 277.495 182.88 0)
		(effects
			(font
				(size 1.27 1.27)
			)
			(justify left bottom)
		)
	)
	(label "LPDDR5_OUT_B.DQ6"
		(at 277.495 177.8 0)
		(effects
			(font
				(size 1.27 1.27)
			)
			(justify left bottom)
		)
	)
	(label "LPDDR5_OUT_B.RDQS1_P"
		(at 277.495 104.14 0)
		(effects
			(font
				(size 1.27 1.27)
			)
			(justify left bottom)
		)
	)
	(label "LPDDR5_IN_B.CK_N"
		(at 209.55 132.08 0)
		(effects
			(font
				(size 1.27 1.27)
			)
			(justify left bottom)
		)
	)
	(label "LPDDR5_IN_B.DQ6"
		(at 277.495 208.28 0)
		(effects
			(font
				(size 1.27 1.27)
			)
			(justify left bottom)
		)
	)
	(label "LPDDR5_OUT_A.DQ14"
		(at 127 154.94 0)
		(effects
			(font
				(size 1.27 1.27)
			)
			(justify left bottom)
		)
	)
	(label "I2C.SCL"
		(at 237.49 40.64 180)
		(effects
			(font
				(size 1.27 1.27)
			)
			(justify right bottom)
		)
	)
	(label "LPDDR5_OUT_A.DQ6"
		(at 127 208.28 0)
		(effects
			(font
				(size 1.27 1.27)
			)
			(justify left bottom)
		)
	)
	(label "LPDDR5_IN_B.CA3"
		(at 209.55 152.4 0)
		(effects
			(font
				(size 1.27 1.27)
			)
			(justify left bottom)
		)
	)
	(label "LPDDR5_IN_A.CA6"
		(at 57.15 160.02 0)
		(effects
			(font
				(size 1.27 1.27)
			)
			(justify left bottom)
		)
	)
	(label "LPDDR5_IN_B.CS1"
		(at 209.55 106.68 0)
		(effects
			(font
				(size 1.27 1.27)
			)
			(justify left bottom)
		)
	)
	(label "LPDDR5_IN_B.DMI0"
		(at 209.55 121.92 0)
		(effects
			(font
				(size 1.27 1.27)
			)
			(justify left bottom)
		)
	)
	(label "LPDDR5_OUT_B.DQ9"
		(at 277.495 116.84 0)
		(effects
			(font
				(size 1.27 1.27)
			)
			(justify left bottom)
		)
	)
	(label "LPDDR5_IN_B.CS0"
		(at 209.55 104.14 0)
		(effects
			(font
				(size 1.27 1.27)
			)
			(justify left bottom)
		)
	)
	(label "LPDDR5_IN_B.DQ15"
		(at 277.495 152.4 0)
		(effects
			(font
				(size 1.27 1.27)
			)
			(justify left bottom)
		)
	)
	(label "LPDDR5_IN_B.CA0"
		(at 209.55 144.78 0)
		(effects
			(font
				(size 1.27 1.27)
			)
			(justify left bottom)
		)
	)
	(label "LPDDR5_OUT_B.DQ14"
		(at 277.495 124.46 0)
		(effects
			(font
				(size 1.27 1.27)
			)
			(justify left bottom)
		)
	)
	(label "LPDDR5_IN_A.DQ0"
		(at 127 190.5 0)
		(effects
			(font
				(size 1.27 1.27)
			)
			(justify left bottom)
		)
	)
	(label "LPDDR5_OUT_B.RDQS0_N"
		(at 277.495 167.64 0)
		(effects
			(font
				(size 1.27 1.27)
			)
			(justify left bottom)
		)
	)
	(label "LPDDR5_OUT_B.DQ13"
		(at 277.495 129.54 0)
		(effects
			(font
				(size 1.27 1.27)
			)
			(justify left bottom)
		)
	)
	(label "LPDDR5_OUT_B.DQ11"
		(at 277.495 119.38 0)
		(effects
			(font
				(size 1.27 1.27)
			)
			(justify left bottom)
		)
	)
	(label "LPDDR5_IN_B.DQ7"
		(at 277.495 210.82 0)
		(effects
			(font
				(size 1.27 1.27)
			)
			(justify left bottom)
		)
	)
	(label "LPDDR5_OUT_A.DQ10"
		(at 127 144.78 0)
		(effects
			(font
				(size 1.27 1.27)
			)
			(justify left bottom)
		)
	)
	(label "LPDDR5_IN_A.DQ1"
		(at 127 185.42 0)
		(effects
			(font
				(size 1.27 1.27)
			)
			(justify left bottom)
		)
	)
	(label "LPDDR5_IN_B.WCK1_N"
		(at 277.495 137.16 0)
		(effects
			(font
				(size 1.27 1.27)
			)
			(justify left bottom)
		)
	)
	(label "LPDDR5_IN_B.CA1"
		(at 209.55 147.32 0)
		(effects
			(font
				(size 1.27 1.27)
			)
			(justify left bottom)
		)
	)
	(label "LPDDR5_IN_A.DMI1"
		(at 57.15 114.3 0)
		(effects
			(font
				(size 1.27 1.27)
			)
			(justify left bottom)
		)
	)
	(label "LPDDR5_OUT_B.DMI0"
		(at 209.55 119.38 0)
		(effects
			(font
				(size 1.27 1.27)
			)
			(justify left bottom)
		)
	)
	(label "LPDDR5_OUT_B.DQ5"
		(at 277.495 172.72 0)
		(effects
			(font
				(size 1.27 1.27)
			)
			(justify left bottom)
		)
	)
	(label "LPDDR5_IN_A.DMI0"
		(at 57.15 119.38 0)
		(effects
			(font
				(size 1.27 1.27)
			)
			(justify left bottom)
		)
	)
	(label "LPDDR5_IN_A.CA5"
		(at 57.15 157.48 0)
		(effects
			(font
				(size 1.27 1.27)
			)
			(justify left bottom)
		)
	)
	(label "LPDDR5_IN_B.WCK0_N"
		(at 277.495 198.12 0)
		(effects
			(font
				(size 1.27 1.27)
			)
			(justify left bottom)
		)
	)
	(label "LPDDR5_OUT_A.DQ3"
		(at 127 213.36 0)
		(effects
			(font
				(size 1.27 1.27)
			)
			(justify left bottom)
		)
	)
	(label "LPDDR5_IN_B.CA4"
		(at 209.55 154.94 0)
		(effects
			(font
				(size 1.27 1.27)
			)
			(justify left bottom)
		)
	)
	(label "LPDDR5_OUT_B.RDQS1_N"
		(at 277.495 106.68 0)
		(effects
			(font
				(size 1.27 1.27)
			)
			(justify left bottom)
		)
	)
	(label "LPDDR5_IN_B.WCK1_P"
		(at 277.495 134.62 0)
		(effects
			(font
				(size 1.27 1.27)
			)
			(justify left bottom)
		)
	)
	(label "LPDDR5_IN_A.DQ5"
		(at 127 172.72 0)
		(effects
			(font
				(size 1.27 1.27)
			)
			(justify left bottom)
		)
	)
	(label "LPDDR5_IN_B.DQ5"
		(at 277.495 203.2 0)
		(effects
			(font
				(size 1.27 1.27)
			)
			(justify left bottom)
		)
	)
	(label "LPDDR5_IN_A.WCK1_P"
		(at 127 104.14 0)
		(effects
			(font
				(size 1.27 1.27)
			)
			(justify left bottom)
		)
	)
	(label "LPDDR5_IN_A.CS1"
		(at 57.15 106.68 0)
		(effects
			(font
				(size 1.27 1.27)
			)
			(justify left bottom)
		)
	)
	(label "LPDDR5_OUT_A.DQ0"
		(at 127 220.98 0)
		(effects
			(font
				(size 1.27 1.27)
			)
			(justify left bottom)
		)
	)
	(label "LPDDR5_IN_A.DQ4"
		(at 127 175.26 0)
		(effects
			(font
				(size 1.27 1.27)
			)
			(justify left bottom)
		)
	)
	(label "LPDDR5_OUT_B.DQ8"
		(at 277.495 111.76 0)
		(effects
			(font
				(size 1.27 1.27)
			)
			(justify left bottom)
		)
	)
	(label "LPDDR5_OUT_A.DQ1"
		(at 127 215.9 0)
		(effects
			(font
				(size 1.27 1.27)
			)
			(justify left bottom)
		)
	)
	(label "LPDDR5_OUT_A.RDQS1_P"
		(at 127 134.62 0)
		(effects
			(font
				(size 1.27 1.27)
			)
			(justify left bottom)
		)
	)
	(label "LPDDR5_IN_B.CA5"
		(at 209.55 157.48 0)
		(effects
			(font
				(size 1.27 1.27)
			)
			(justify left bottom)
		)
	)
	(label "LPDDR5_OUT_B.DQ10"
		(at 277.495 114.3 0)
		(effects
			(font
				(size 1.27 1.27)
			)
			(justify left bottom)
		)
	)
	(label "LPDDR5_OUT_A.DQ13"
		(at 127 160.02 0)
		(effects
			(font
				(size 1.27 1.27)
			)
			(justify left bottom)
		)
	)
	(label "LPDDR5_OUT_B.DQ12"
		(at 277.495 127 0)
		(effects
			(font
				(size 1.27 1.27)
			)
			(justify left bottom)
		)
	)
	(label "LPDDR5_IN_A.CA0"
		(at 57.15 144.78 0)
		(effects
			(font
				(size 1.27 1.27)
			)
			(justify left bottom)
		)
	)
	(label "LPDDR5_OUT_A.DQ2"
		(at 127 218.44 0)
		(effects
			(font
				(size 1.27 1.27)
			)
			(justify left bottom)
		)
	)
	(label "LPDDR5_IN_B.DQ8"
		(at 277.495 142.24 0)
		(effects
			(font
				(size 1.27 1.27)
			)
			(justify left bottom)
		)
	)
	(label "LPDDR5_IN_A.CS0"
		(at 57.15 104.14 0)
		(effects
			(font
				(size 1.27 1.27)
			)
			(justify left bottom)
		)
	)
	(label "LPDDR5_OUT_B.RDQS0_P"
		(at 277.495 165.1 0)
		(effects
			(font
				(size 1.27 1.27)
			)
			(justify left bottom)
		)
	)
	(label "LPDDR5_IN_A.DQ3"
		(at 127 182.88 0)
		(effects
			(font
				(size 1.27 1.27)
			)
			(justify left bottom)
		)
	)
	(label "LPDDR5_OUT_B.DQ1"
		(at 277.495 185.42 0)
		(effects
			(font
				(size 1.27 1.27)
			)
			(justify left bottom)
		)
	)
	(label "LPDDR5_IN_B.DMI1"
		(at 209.55 116.84 0)
		(effects
			(font
				(size 1.27 1.27)
			)
			(justify left bottom)
		)
	)
	(label "LPDDR5_OUT_A.DQ8"
		(at 127 142.24 0)
		(effects
			(font
				(size 1.27 1.27)
			)
			(justify left bottom)
		)
	)
	(label "LPDDR5_IN_A.CK_N"
		(at 57.15 132.08 0)
		(effects
			(font
				(size 1.27 1.27)
			)
			(justify left bottom)
		)
	)
	(label "LPDDR5_OUT_B.DMI1"
		(at 209.55 114.3 0)
		(effects
			(font
				(size 1.27 1.27)
			)
			(justify left bottom)
		)
	)
	(label "LPDDR5_IN_A.DQ8"
		(at 127 111.76 0)
		(effects
			(font
				(size 1.27 1.27)
			)
			(justify left bottom)
		)
	)
	(label "HSDA"
		(at 202.565 43.18 180)
		(effects
			(font
				(size 1.27 1.27)
			)
			(justify right bottom)
		)
	)
	(label "LPDDR5_OUT_A.DQ5"
		(at 127 203.2 0)
		(effects
			(font
				(size 1.27 1.27)
			)
			(justify left bottom)
		)
	)
	(label "LPDDR5_OUT_A.DQ15"
		(at 127 152.4 0)
		(effects
			(font
				(size 1.27 1.27)
			)
			(justify left bottom)
		)
	)
	(label "LPDDR5_IN_B.CA2"
		(at 209.55 149.86 0)
		(effects
			(font
				(size 1.27 1.27)
			)
			(justify left bottom)
		)
	)
	(label "LPDDR5_IN_A.WCK0_N"
		(at 127 167.64 0)
		(effects
			(font
				(size 1.27 1.27)
			)
			(justify left bottom)
		)
	)
	(label "LPDDR5_IN_B.DQ4"
		(at 277.495 205.74 0)
		(effects
			(font
				(size 1.27 1.27)
			)
			(justify left bottom)
		)
	)
	(label "LPDDR5_OUT_A.DQ9"
		(at 127 147.32 0)
		(effects
			(font
				(size 1.27 1.27)
			)
			(justify left bottom)
		)
	)
	(label "LPDDR5_IN_A.WCK1_N"
		(at 127 106.68 0)
		(effects
			(font
				(size 1.27 1.27)
			)
			(justify left bottom)
		)
	)
	(label "LPDDR5_IN_B.DQ9"
		(at 277.495 147.32 0)
		(effects
			(font
				(size 1.27 1.27)
			)
			(justify left bottom)
		)
	)
	(label "LPDDR5_OUT_A.DQ4"
		(at 127 205.74 0)
		(effects
			(font
				(size 1.27 1.27)
			)
			(justify left bottom)
		)
	)
	(label "LPDDR5_OUT_B.DQ0"
		(at 277.495 190.5 0)
		(effects
			(font
				(size 1.27 1.27)
			)
			(justify left bottom)
		)
	)
	(label "LPDDR5_IN_B.DQ2"
		(at 277.495 218.44 0)
		(effects
			(font
				(size 1.27 1.27)
			)
			(justify left bottom)
		)
	)
	(label "LPDDR5_IN_B.WCK0_P"
		(at 277.495 195.58 0)
		(effects
			(font
				(size 1.27 1.27)
			)
			(justify left bottom)
		)
	)
	(label "LPDDR5_IN_A.CA3"
		(at 57.15 152.4 0)
		(effects
			(font
				(size 1.27 1.27)
			)
			(justify left bottom)
		)
	)
	(label "LPDDR5_IN_B.DQ10"
		(at 277.495 144.78 0)
		(effects
			(font
				(size 1.27 1.27)
			)
			(justify left bottom)
		)
	)
	(label "LPDDR5_IN_B.DQ1"
		(at 277.495 215.9 0)
		(effects
			(font
				(size 1.27 1.27)
			)
			(justify left bottom)
		)
	)
	(label "I2C.SDA"
		(at 237.49 43.18 180)
		(effects
			(font
				(size 1.27 1.27)
			)
			(justify right bottom)
		)
	)
	(label "LPDDR5_OUT_A.DQ11"
		(at 127 149.86 0)
		(effects
			(font
				(size 1.27 1.27)
			)
			(justify left bottom)
		)
	)
	(label "LPDDR5_IN_A.DQ13"
		(at 127 129.54 0)
		(effects
			(font
				(size 1.27 1.27)
			)
			(justify left bottom)
		)
	)
	(label "LPDDR5_IN_A.DQ12"
		(at 127 127 0)
		(effects
			(font
				(size 1.27 1.27)
			)
			(justify left bottom)
		)
	)
	(label "LPDDR5_IN_A.DQ6"
		(at 127 177.8 0)
		(effects
			(font
				(size 1.27 1.27)
			)
			(justify left bottom)
		)
	)
	(label "LPDDR5_IN_B.DQ11"
		(at 277.495 149.86 0)
		(effects
			(font
				(size 1.27 1.27)
			)
			(justify left bottom)
		)
	)
	(label "LPDDR5_IN_A.DQ15"
		(at 127 121.92 0)
		(effects
			(font
				(size 1.27 1.27)
			)
			(justify left bottom)
		)
	)
	(label "LPDDR5_OUT_B.DQ15"
		(at 277.495 121.92 0)
		(effects
			(font
				(size 1.27 1.27)
			)
			(justify left bottom)
		)
	)
	(label "LPDDR5_OUT_B.DQ7"
		(at 277.495 180.34 0)
		(effects
			(font
				(size 1.27 1.27)
			)
			(justify left bottom)
		)
	)
	(label "LPDDR5_IN_A.DQ11"
		(at 127 119.38 0)
		(effects
			(font
				(size 1.27 1.27)
			)
			(justify left bottom)
		)
	)
	(label "LPDDR5_IN_A.DQ7"
		(at 127 180.34 0)
		(effects
			(font
				(size 1.27 1.27)
			)
			(justify left bottom)
		)
	)
	(label "LPDDR5_IN_B.DQ14"
		(at 277.495 154.94 0)
		(effects
			(font
				(size 1.27 1.27)
			)
			(justify left bottom)
		)
	)
	(label "LPDDR5_OUT_B.DQ2"
		(at 277.495 187.96 0)
		(effects
			(font
				(size 1.27 1.27)
			)
			(justify left bottom)
		)
	)
	(label "LPDDR5_OUT_B.DQ4"
		(at 277.495 175.26 0)
		(effects
			(font
				(size 1.27 1.27)
			)
			(justify left bottom)
		)
	)
	(label "LPDDR5_IN_A.DQ9"
		(at 127 116.84 0)
		(effects
			(font
				(size 1.27 1.27)
			)
			(justify left bottom)
		)
	)
	(label "LPDDR5_IN_B.DQ13"
		(at 277.495 160.02 0)
		(effects
			(font
				(size 1.27 1.27)
			)
			(justify left bottom)
		)
	)
	(label "LPDDR5_IN_A.DQ14"
		(at 127 124.46 0)
		(effects
			(font
				(size 1.27 1.27)
			)
			(justify left bottom)
		)
	)
	(label "LPDDR5_IN_A.DQ2"
		(at 127 187.96 0)
		(effects
			(font
				(size 1.27 1.27)
			)
			(justify left bottom)
		)
	)
	(label "LPDDR5_OUT_A.DMI1"
		(at 57.15 116.84 0)
		(effects
			(font
				(size 1.27 1.27)
			)
			(justify left bottom)
		)
	)
	(label "LPDDR5_IN_B.DQ0"
		(at 277.495 220.98 0)
		(effects
			(font
				(size 1.27 1.27)
			)
			(justify left bottom)
		)
	)
	(label "LPDDR5_OUT_A.DQ12"
		(at 127 157.48 0)
		(effects
			(font
				(size 1.27 1.27)
			)
			(justify left bottom)
		)
	)
	(label "LPDDR5_IN_A.CA2"
		(at 57.15 149.86 0)
		(effects
			(font
				(size 1.27 1.27)
			)
			(justify left bottom)
		)
	)
	(label "LPDDR5_IN_B.CA6"
		(at 209.55 160.02 0)
		(effects
			(font
				(size 1.27 1.27)
			)
			(justify left bottom)
		)
	)
	(label "LPDDR5_OUT_A.DMI0"
		(at 57.15 121.92 0)
		(effects
			(font
				(size 1.27 1.27)
			)
			(justify left bottom)
		)
	)
	(label "LPDDR5_IN_A.CK_P"
		(at 57.15 129.54 0)
		(effects
			(font
				(size 1.27 1.27)
			)
			(justify left bottom)
		)
	)
	(label "LPDDR5_IN_B.DQ12"
		(at 277.495 157.48 0)
		(effects
			(font
				(size 1.27 1.27)
			)
			(justify left bottom)
		)
	)
	(label "HSCL"
		(at 202.565 40.64 180)
		(effects
			(font
				(size 1.27 1.27)
			)
			(justify right bottom)
		)
	)
	(label "LPDDR5_IN_A.CA1"
		(at 57.15 147.32 0)
		(effects
			(font
				(size 1.27 1.27)
			)
			(justify left bottom)
		)
	)
	(label "LPDDR5_IN_A.DQ10"
		(at 127 114.3 0)
		(effects
			(font
				(size 1.27 1.27)
			)
			(justify left bottom)
		)
	)
	(label "LPDDR5_IN_A.WCK0_P"
		(at 127 165.1 0)
		(effects
			(font
				(size 1.27 1.27)
			)
			(justify left bottom)
		)
	)
	(label "LPDDR5_OUT_A.RDQS0_N"
		(at 127 198.12 0)
		(effects
			(font
				(size 1.27 1.27)
			)
			(justify left bottom)
		)
	)
	(label "LPDDR5_OUT_A.DQ7"
		(at 127 210.82 0)
		(effects
			(font
				(size 1.27 1.27)
			)
			(justify left bottom)
		)
	)
	(hierarchical_label "PWR_EN"
		(shape output)
		(at 205.74 30.48 0)
		(effects
			(font
				(size 1.27 1.27)
			)
			(justify left)
		)
	)
	(hierarchical_label "LPDDR5_IN_A{LPDDR5}"
		(shape output)
		(at 161.925 91.44 0)
		(effects
			(font
				(size 1.27 1.27)
			)
			(justify left)
		)
	)
	(hierarchical_label "LPDDR5_IN_B{LPDDR5}"
		(shape output)
		(at 314.325 91.44 0)
		(effects
			(font
				(size 1.27 1.27)
			)
			(justify left)
		)
	)
	(hierarchical_label "LPDDR5_OUT_A{LPDDR5}"
		(shape input)
		(at 167.005 232.41 0)
		(effects
			(font
				(size 1.27 1.27)
			)
			(justify left)
		)
	)
	(hierarchical_label "PWRGD"
		(shape input)
		(at 197.485 48.26 0)
		(effects
			(font
				(size 1.27 1.27)
			)
			(justify left)
		)
	)
	(hierarchical_label "I2C{SDA,SCL}"
		(shape bidirectional)
		(at 245.745 48.26 0)
		(effects
			(font
				(size 1.27 1.27)
			)
			(justify left)
		)
	)
	(hierarchical_label "~{RESET}"
		(shape output)
		(at 205.74 33.02 0)
		(effects
			(font
				(size 1.27 1.27)
			)
			(justify left)
		)
	)
	(hierarchical_label "LPDDR5_OUT_B{LPDDR5}"
		(shape input)
		(at 319.405 232.41 0)
		(effects
			(font
				(size 1.27 1.27)
			)
			(justify left)
		)
	)
	(symbol
		(lib_id "lpddr5-testbed:Edge_Conn_Bus_DDR5_SODIMM_1xDetectPin")
		(at 170.18 30.48 0)
		(unit 1)
		(exclude_from_sim no)
		(in_bom yes)
		(on_board yes)
		(dnp no)
		(property "Reference" "J1"
			(at 182.88 26.67 0)
			(effects
				(font
					(size 1.27 1.27)
				)
			)
		)
		(property "Value" "PCB-Edge_SODIMM_2x131_LPDDR5_Testbed"
			(at 185.42 54.61 0)
			(effects
				(font
					(size 1.27 1.27)
				)
			)
		)
		(property "Footprint" "lpddr5-testbed-footprints:Edge_Conn_Bus_DDR5_SODIMM"
			(at 222.25 43.18 0)
			(effects
				(font
					(size 1.27 1.27)
				)
				(justify left bottom)
				(hide yes)
			)
		)
		(property "Datasheet" "https://cdn.amphenol-cs.com/media/wysiwyg/files/drawing/10162416.pdf"
			(at 222.25 40.64 0)
			(effects
				(font
					(size 1.27 1.27)
				)
				(justify left bottom)
				(hide yes)
			)
		)
		(property "Description" ""
			(at 170.18 30.48 0)
			(effects
				(font
					(size 1.27 1.27)
				)
			)
		)
		(property "MPN" ""
			(at 222.25 38.1 0)
			(effects
				(font
					(size 1.27 1.27)
				)
				(justify left bottom)
				(hide yes)
			)
		)
		(property "Manufacturer" ""
			(at 222.25 35.56 0)
			(effects
				(font
					(size 1.27 1.27)
				)
				(justify left bottom)
				(hide yes)
			)
		)
		(property "Author" "Antmicro"
			(at 222.25 48.26 0)
			(effects
				(font
					(size 1.27 1.27)
				)
				(justify left bottom)
				(hide yes)
			)
		)
		(property "License" "Apache-2.0"
			(at 222.25 45.72 0)
			(effects
				(font
					(size 1.27 1.27)
				)
				(justify left bottom)
				(hide yes)
			)
		)
		(pin "1"
		)
		(pin "10"
		)
		(pin "101"
		)
		(pin "104"
		)
		(pin "105"
		)
		(pin "108"
		)
		(pin "111"
		)
		(pin "112"
		)
		(pin "117"
		)
		(pin "118"
		)
		(pin "123"
		)
		(pin "124"
		)
		(pin "128"
		)
		(pin "129"
		)
		(pin "13"
		)
		(pin "130"
		)
		(pin "135"
		)
		(pin "136"
		)
		(pin "14"
		)
		(pin "141"
		)
		(pin "142"
		)
		(pin "143"
		)
		(pin "147"
		)
		(pin "148"
		)
		(pin "153"
		)
		(pin "154"
		)
		(pin "159"
		)
		(pin "160"
		)
		(pin "163"
		)
		(pin "166"
		)
		(pin "167"
		)
		(pin "17"
		)
		(pin "170"
		)
		(pin "173"
		)
		(pin "174"
		)
		(pin "177"
		)
		(pin "178"
		)
		(pin "18"
		)
		(pin "181"
		)
		(pin "182"
		)
		(pin "185"
		)
		(pin "186"
		)
		(pin "189"
		)
		(pin "192"
		)
		(pin "193"
		)
		(pin "196"
		)
		(pin "197"
		)
		(pin "2"
		)
		(pin "200"
		)
		(pin "201"
		)
		(pin "204"
		)
		(pin "205"
		)
		(pin "208"
		)
		(pin "21"
		)
		(pin "211"
		)
		(pin "212"
		)
		(pin "215"
		)
		(pin "216"
		)
		(pin "219"
		)
		(pin "220"
		)
		(pin "223"
		)
		(pin "224"
		)
		(pin "227"
		)
		(pin "228"
		)
		(pin "231"
		)
		(pin "234"
		)
		(pin "235"
		)
		(pin "238"
		)
		(pin "239"
		)
		(pin "24"
		)
		(pin "242"
		)
		(pin "243"
		)
		(pin "246"
		)
		(pin "247"
		)
		(pin "25"
		)
		(pin "250"
		)
		(pin "253"
		)
		(pin "254"
		)
		(pin "257"
		)
		(pin "258"
		)
		(pin "261"
		)
		(pin "262"
		)
		(pin "28"
		)
		(pin "29"
		)
		(pin "3"
		)
		(pin "32"
		)
		(pin "33"
		)
		(pin "36"
		)
		(pin "37"
		)
		(pin "4"
		)
		(pin "40"
		)
		(pin "43"
		)
		(pin "44"
		)
		(pin "47"
		)
		(pin "48"
		)
		(pin "5"
		)
		(pin "51"
		)
		(pin "52"
		)
		(pin "55"
		)
		(pin "56"
		)
		(pin "59"
		)
		(pin "6"
		)
		(pin "60"
		)
		(pin "63"
		)
		(pin "66"
		)
		(pin "67"
		)
		(pin "7"
		)
		(pin "70"
		)
		(pin "71"
		)
		(pin "74"
		)
		(pin "75"
		)
		(pin "78"
		)
		(pin "79"
		)
		(pin "8"
		)
		(pin "82"
		)
		(pin "85"
		)
		(pin "86"
		)
		(pin "89"
		)
		(pin "9"
		)
		(pin "90"
		)
		(pin "93"
		)
		(pin "94"
		)
		(pin "97"
		)
		(pin "98"
		)
		(pin "100"
		)
		(pin "102"
		)
		(pin "103"
		)
		(pin "106"
		)
		(pin "107"
		)
		(pin "109"
		)
		(pin "11"
		)
		(pin "110"
		)
		(pin "113"
		)
		(pin "114"
		)
		(pin "115"
		)
		(pin "116"
		)
		(pin "119"
		)
		(pin "12"
		)
		(pin "120"
		)
		(pin "121"
		)
		(pin "122"
		)
		(pin "125"
		)
		(pin "126"
		)
		(pin "127"
		)
		(pin "131"
		)
		(pin "132"
		)
		(pin "133"
		)
		(pin "134"
		)
		(pin "15"
		)
		(pin "16"
		)
		(pin "19"
		)
		(pin "20"
		)
		(pin "22"
		)
		(pin "23"
		)
		(pin "26"
		)
		(pin "27"
		)
		(pin "30"
		)
		(pin "31"
		)
		(pin "34"
		)
		(pin "35"
		)
		(pin "38"
		)
		(pin "39"
		)
		(pin "41"
		)
		(pin "42"
		)
		(pin "45"
		)
		(pin "46"
		)
		(pin "49"
		)
		(pin "50"
		)
		(pin "53"
		)
		(pin "54"
		)
		(pin "57"
		)
		(pin "58"
		)
		(pin "61"
		)
		(pin "62"
		)
		(pin "64"
		)
		(pin "65"
		)
		(pin "68"
		)
		(pin "69"
		)
		(pin "72"
		)
		(pin "73"
		)
		(pin "76"
		)
		(pin "77"
		)
		(pin "80"
		)
		(pin "81"
		)
		(pin "83"
		)
		(pin "84"
		)
		(pin "87"
		)
		(pin "88"
		)
		(pin "91"
		)
		(pin "92"
		)
		(pin "95"
		)
		(pin "96"
		)
		(pin "99"
		)
		(pin "137"
		)
		(pin "138"
		)
		(pin "139"
		)
		(pin "140"
		)
		(pin "144"
		)
		(pin "145"
		)
		(pin "146"
		)
		(pin "149"
		)
		(pin "150"
		)
		(pin "151"
		)
		(pin "152"
		)
		(pin "155"
		)
		(pin "156"
		)
		(pin "157"
		)
		(pin "158"
		)
		(pin "161"
		)
		(pin "162"
		)
		(pin "164"
		)
		(pin "165"
		)
		(pin "168"
		)
		(pin "169"
		)
		(pin "171"
		)
		(pin "172"
		)
		(pin "175"
		)
		(pin "176"
		)
		(pin "179"
		)
		(pin "180"
		)
		(pin "183"
		)
		(pin "184"
		)
		(pin "187"
		)
		(pin "188"
		)
		(pin "190"
		)
		(pin "191"
		)
		(pin "194"
		)
		(pin "195"
		)
		(pin "198"
		)
		(pin "199"
		)
		(pin "202"
		)
		(pin "203"
		)
		(pin "206"
		)
		(pin "207"
		)
		(pin "209"
		)
		(pin "210"
		)
		(pin "213"
		)
		(pin "214"
		)
		(pin "217"
		)
		(pin "218"
		)
		(pin "221"
		)
		(pin "222"
		)
		(pin "225"
		)
		(pin "226"
		)
		(pin "229"
		)
		(pin "230"
		)
		(pin "232"
		)
		(pin "233"
		)
		(pin "236"
		)
		(pin "237"
		)
		(pin "240"
		)
		(pin "241"
		)
		(pin "244"
		)
		(pin "245"
		)
		(pin "248"
		)
		(pin "249"
		)
		(pin "251"
		)
		(pin "252"
		)
		(pin "255"
		)
		(pin "256"
		)
		(pin "259"
		)
		(pin "260"
		)
		(instances
			(project ""
				(path ""
					(reference "J1")
					(unit 1)
				)
			)
		)
	)
	(symbol
		(lib_id "antmicroResistors0402:R_0R_0402")
		(at 219.71 43.18 0)
		(mirror x)
		(unit 1)
		(exclude_from_sim no)
		(in_bom yes)
		(on_board yes)
		(dnp no)
		(property "Reference" "R27"
			(at 219.71 41.91 0)
			(effects
				(font
					(size 1.27 1.27)
					(thickness 0.15)
				)
				(justify right)
			)
		)
		(property "Value" "R_0R_0402"
			(at 240.03 30.48 0)
			(effects
				(font
					(size 1.27 1.27)
					(thickness 0.15)
				)
				(justify left bottom)
				(hide yes)
			)
		)
		(property "Footprint" "antmicro-footprints:R_0402_1005Metric"
			(at 240.03 27.94 0)
			(effects
				(font
					(size 1.27 1.27)
					(thickness 0.15)
				)
				(justify left bottom)
				(hide yes)
			)
		)
		(property "Datasheet" "https://industrial.panasonic.com/cdbs/www-data/pdf/RDA0000/AOA0000C301.pdf"
			(at 240.03 25.4 0)
			(effects
				(font
					(size 1.27 1.27)
					(thickness 0.15)
				)
				(justify left bottom)
				(hide yes)
			)
		)
		(property "Description" ""
			(at 219.71 43.18 0)
			(effects
				(font
					(size 1.27 1.27)
				)
			)
		)
		(property "MPN" "ERJ2GE0R00X"
			(at 240.03 22.86 0)
			(effects
				(font
					(size 1.27 1.27)
					(thickness 0.15)
				)
				(justify left bottom)
				(hide yes)
			)
		)
		(property "Manufacturer" "Panasonic"
			(at 240.03 20.32 0)
			(effects
				(font
					(size 1.27 1.27)
					(thickness 0.15)
				)
				(justify left bottom)
				(hide yes)
			)
		)
		(property "License" "Apache-2.0"
			(at 240.03 17.78 0)
			(effects
				(font
					(size 1.27 1.27)
					(thickness 0.15)
				)
				(justify left bottom)
				(hide yes)
			)
		)
		(property "Author" "Antmicro"
			(at 240.03 15.24 0)
			(effects
				(font
					(size 1.27 1.27)
					(thickness 0.15)
				)
				(justify left bottom)
				(hide yes)
			)
		)
		(property "Val" "0R"
			(at 227.33 41.91 0)
			(effects
				(font
					(size 1.27 1.27)
					(thickness 0.15)
				)
				(justify right)
			)
		)
		(property "Tolerance" "~"
			(at 240.03 33.02 0)
			(effects
				(font
					(size 1.27 1.27)
				)
				(justify left bottom)
				(hide yes)
			)
		)
		(property "Current" "1A"
			(at 240.03 12.7 0)
			(effects
				(font
					(size 1.27 1.27)
					(thickness 0.15)
				)
				(justify left bottom)
				(hide yes)
			)
		)
		(pin "1"
		)
		(pin "2"
		)
		(instances
			(project ""
				(path ""
					(reference "R27")
					(unit 1)
				)
			)
		)
	)
	(symbol
		(lib_id "antmicropower:GND")
		(at 161.29 52.07 0)
		(unit 1)
		(exclude_from_sim no)
		(in_bom yes)
		(on_board yes)
		(dnp no)
		(property "Reference" "#PWR0220"
			(at 161.29 58.42 0)
			(effects
				(font
					(size 1.27 1.27)
				)
				(hide yes)
			)
		)
		(property "Value" "GND"
			(at 161.29 55.88 0)
			(effects
				(font
					(size 1.27 1.27)
				)
			)
		)
		(property "Footprint" ""
			(at 161.29 52.07 0)
			(effects
				(font
					(size 1.27 1.27)
				)
				(hide yes)
			)
		)
		(property "Datasheet" ""
			(at 161.29 52.07 0)
			(effects
				(font
					(size 1.27 1.27)
				)
				(hide yes)
			)
		)
		(property "Description" ""
			(at 161.29 52.07 0)
			(effects
				(font
					(size 1.27 1.27)
				)
			)
		)
		(pin "1"
		)
		(instances
			(project ""
				(path ""
					(reference "#PWR0220")
					(unit 1)
				)
			)
		)
	)
	(symbol
		(lib_id "antmicroResistors0402:R_0R_0402")
		(at 219.71 40.64 0)
		(mirror x)
		(unit 1)
		(exclude_from_sim no)
		(in_bom yes)
		(on_board yes)
		(dnp no)
		(property "Reference" "R26"
			(at 219.71 39.37 0)
			(effects
				(font
					(size 1.27 1.27)
					(thickness 0.15)
				)
				(justify right)
			)
		)
		(property "Value" "R_0R_0402"
			(at 240.03 27.94 0)
			(effects
				(font
					(size 1.27 1.27)
					(thickness 0.15)
				)
				(justify left bottom)
				(hide yes)
			)
		)
		(property "Footprint" "antmicro-footprints:R_0402_1005Metric"
			(at 240.03 25.4 0)
			(effects
				(font
					(size 1.27 1.27)
					(thickness 0.15)
				)
				(justify left bottom)
				(hide yes)
			)
		)
		(property "Datasheet" "https://industrial.panasonic.com/cdbs/www-data/pdf/RDA0000/AOA0000C301.pdf"
			(at 240.03 22.86 0)
			(effects
				(font
					(size 1.27 1.27)
					(thickness 0.15)
				)
				(justify left bottom)
				(hide yes)
			)
		)
		(property "Description" ""
			(at 219.71 40.64 0)
			(effects
				(font
					(size 1.27 1.27)
				)
			)
		)
		(property "MPN" "ERJ2GE0R00X"
			(at 240.03 20.32 0)
			(effects
				(font
					(size 1.27 1.27)
					(thickness 0.15)
				)
				(justify left bottom)
				(hide yes)
			)
		)
		(property "Manufacturer" "Panasonic"
			(at 240.03 17.78 0)
			(effects
				(font
					(size 1.27 1.27)
					(thickness 0.15)
				)
				(justify left bottom)
				(hide yes)
			)
		)
		(property "License" "Apache-2.0"
			(at 240.03 15.24 0)
			(effects
				(font
					(size 1.27 1.27)
					(thickness 0.15)
				)
				(justify left bottom)
				(hide yes)
			)
		)
		(property "Author" "Antmicro"
			(at 240.03 12.7 0)
			(effects
				(font
					(size 1.27 1.27)
					(thickness 0.15)
				)
				(justify left bottom)
				(hide yes)
			)
		)
		(property "Val" "0R"
			(at 227.33 39.37 0)
			(effects
				(font
					(size 1.27 1.27)
					(thickness 0.15)
				)
				(justify right)
			)
		)
		(property "Tolerance" "~"
			(at 240.03 30.48 0)
			(effects
				(font
					(size 1.27 1.27)
				)
				(justify left bottom)
				(hide yes)
			)
		)
		(property "Current" "1A"
			(at 240.03 10.16 0)
			(effects
				(font
					(size 1.27 1.27)
					(thickness 0.15)
				)
				(justify left bottom)
				(hide yes)
			)
		)
		(pin "1"
		)
		(pin "2"
		)
		(instances
			(project ""
				(path ""
					(reference "R26")
					(unit 1)
				)
			)
		)
	)
	(symbol
		(lib_id "antmicropower:+5V")
		(at 161.29 25.4 0)
		(unit 1)
		(exclude_from_sim no)
		(in_bom yes)
		(on_board yes)
		(dnp no)
		(property "Reference" "#PWR0142"
			(at 176.53 27.94 0)
			(effects
				(font
					(size 1.27 1.27)
					(thickness 0.15)
				)
				(justify left bottom)
				(hide yes)
			)
		)
		(property "Value" "+5V"
			(at 161.29 21.59 0)
			(effects
				(font
					(size 1.27 1.27)
					(thickness 0.15)
				)
			)
		)
		(property "Footprint" ""
			(at 176.53 33.02 0)
			(effects
				(font
					(size 1.27 1.27)
					(thickness 0.15)
				)
				(justify left bottom)
				(hide yes)
			)
		)
		(property "Datasheet" ""
			(at 176.53 35.56 0)
			(effects
				(font
					(size 1.27 1.27)
					(thickness 0.15)
				)
				(justify left bottom)
				(hide yes)
			)
		)
		(property "Description" ""
			(at 161.29 25.4 0)
			(effects
				(font
					(size 1.27 1.27)
				)
			)
		)
		(property "Author" "Antmicro"
			(at 176.53 33.02 0)
			(effects
				(font
					(size 1.27 1.27)
					(thickness 0.15)
				)
				(justify left bottom)
				(hide yes)
			)
		)
		(property "License" "Apache-2.0"
			(at 176.53 35.56 0)
			(effects
				(font
					(size 1.27 1.27)
					(thickness 0.15)
				)
				(justify left bottom)
				(hide yes)
			)
		)
		(pin "1"
		)
		(instances
			(project ""
				(path ""
					(reference "#PWR0142")
					(unit 1)
				)
			)
		)
	)
	(symbol
		(lib_id "antmicropower:+1V8")
		(at 248.285 58.42 0)
		(unit 1)
		(exclude_from_sim no)
		(in_bom yes)
		(on_board yes)
		(dnp no)
		(fields_autoplaced yes)
		(property "Reference" "#PWR0140"
			(at 263.525 60.96 0)
			(effects
				(font
					(size 1.27 1.27)
					(thickness 0.15)
				)
				(justify left bottom)
				(hide yes)
			)
		)
		(property "Value" "+1V8"
			(at 248.285 53.34 0)
			(effects
				(font
					(size 1.27 1.27)
					(thickness 0.15)
				)
			)
		)
		(property "Footprint" ""
			(at 263.525 66.04 0)
			(effects
				(font
					(size 1.27 1.27)
					(thickness 0.15)
				)
				(justify left bottom)
				(hide yes)
			)
		)
		(property "Datasheet" ""
			(at 263.525 68.58 0)
			(effects
				(font
					(size 1.27 1.27)
					(thickness 0.15)
				)
				(justify left bottom)
				(hide yes)
			)
		)
		(property "Description" ""
			(at 248.285 58.42 0)
			(effects
				(font
					(size 1.27 1.27)
				)
			)
		)
		(property "Author" "Antmicro"
			(at 263.525 66.04 0)
			(effects
				(font
					(size 1.27 1.27)
					(thickness 0.15)
				)
				(justify left bottom)
				(hide yes)
			)
		)
		(property "License" "Apache-2.0"
			(at 263.525 68.58 0)
			(effects
				(font
					(size 1.27 1.27)
					(thickness 0.15)
				)
				(justify left bottom)
				(hide yes)
			)
		)
		(pin "1"
		)
		(instances
			(project ""
				(path ""
					(reference "#PWR0140")
					(unit 1)
				)
			)
		)
	)
	(symbol
		(lib_id "antmicroResistors0402:R_200k_0402")
		(at 161.29 34.29 270)
		(unit 1)
		(exclude_from_sim no)
		(in_bom no)
		(on_board yes)
		(dnp yes)
		(property "Reference" "R28"
			(at 162.56 35.56 90)
			(effects
				(font
					(size 1.27 1.27)
					(thickness 0.15)
				)
				(justify left)
			)
		)
		(property "Value" "R_200k_0402"
			(at 148.59 54.61 0)
			(effects
				(font
					(size 1.27 1.27)
					(thickness 0.15)
				)
				(justify left bottom)
				(hide yes)
			)
		)
		(property "Footprint" "antmicro-footprints:R_0402_1005Metric"
			(at 146.05 54.61 0)
			(effects
				(font
					(size 1.27 1.27)
					(thickness 0.15)
				)
				(justify left bottom)
				(hide yes)
			)
		)
		(property "Datasheet" "https://www.bourns.com/docs/product-datasheets/cr.pdf"
			(at 143.51 54.61 0)
			(effects
				(font
					(size 1.27 1.27)
					(thickness 0.15)
				)
				(justify left bottom)
				(hide yes)
			)
		)
		(property "Description" ""
			(at 161.29 34.29 0)
			(effects
				(font
					(size 1.27 1.27)
				)
			)
		)
		(property "MPN" "CR0402-FX-2003GLF"
			(at 140.97 54.61 0)
			(effects
				(font
					(size 1.27 1.27)
					(thickness 0.15)
				)
				(justify left bottom)
				(hide yes)
			)
		)
		(property "Manufacturer" "Bourns"
			(at 138.43 54.61 0)
			(effects
				(font
					(size 1.27 1.27)
					(thickness 0.15)
				)
				(justify left bottom)
				(hide yes)
			)
		)
		(property "License" "Apache-2.0"
			(at 135.89 54.61 0)
			(effects
				(font
					(size 1.27 1.27)
					(thickness 0.15)
				)
				(justify left bottom)
				(hide yes)
			)
		)
		(property "Author" "Antmicro"
			(at 133.35 54.61 0)
			(effects
				(font
					(size 1.27 1.27)
					(thickness 0.15)
				)
				(justify left bottom)
				(hide yes)
			)
		)
		(property "Val" "200k"
			(at 162.56 38.1 90)
			(effects
				(font
					(size 1.27 1.27)
					(thickness 0.15)
				)
				(justify left)
			)
		)
		(property "Tolerance" "1%"
			(at 151.13 54.61 0)
			(effects
				(font
					(size 1.27 1.27)
				)
				(justify left bottom)
				(hide yes)
			)
		)
		(pin "1"
		)
		(pin "2"
		)
		(instances
			(project ""
				(path ""
					(reference "R28")
					(unit 1)
				)
			)
		)
	)
	(symbol
		(lib_id "antmicroCapacitors0402:C_4u7_0402")
		(at 248.285 64.77 90)
		(unit 1)
		(exclude_from_sim no)
		(in_bom yes)
		(on_board yes)
		(dnp no)
		(property "Reference" "C7"
			(at 248.92 60.325 90)
			(effects
				(font
					(size 1.27 1.27)
					(thickness 0.15)
				)
				(justify right)
			)
		)
		(property "Value" "C_4u7_0402"
			(at 258.445 44.45 0)
			(effects
				(font
					(size 1.27 1.27)
					(thickness 0.15)
				)
				(justify left bottom)
				(hide yes)
			)
		)
		(property "Footprint" "antmicro-footprints:C_0402_1005Metric"
			(at 260.985 44.45 0)
			(effects
				(font
					(size 1.27 1.27)
					(thickness 0.15)
				)
				(justify left bottom)
				(hide yes)
			)
		)
		(property "Datasheet" "https://www.murata.com/products/productdetail?partno=GRM155R61A475MEAA%23"
			(at 263.525 44.45 0)
			(effects
				(font
					(size 1.27 1.27)
					(thickness 0.15)
				)
				(justify left bottom)
				(hide yes)
			)
		)
		(property "Description" ""
			(at 248.285 64.77 0)
			(effects
				(font
					(size 1.27 1.27)
				)
			)
		)
		(property "MPN" "GRM155R61A475MEAAD"
			(at 266.065 44.45 0)
			(effects
				(font
					(size 1.27 1.27)
					(thickness 0.15)
				)
				(justify left bottom)
				(hide yes)
			)
		)
		(property "Manufacturer" "Murata"
			(at 268.605 44.45 0)
			(effects
				(font
					(size 1.27 1.27)
					(thickness 0.15)
				)
				(justify left bottom)
				(hide yes)
			)
		)
		(property "License" "Apache-2.0"
			(at 271.145 44.45 0)
			(effects
				(font
					(size 1.27 1.27)
					(thickness 0.15)
				)
				(justify left bottom)
				(hide yes)
			)
		)
		(property "Author" "Antmicro"
			(at 273.685 44.45 0)
			(effects
				(font
					(size 1.27 1.27)
					(thickness 0.15)
				)
				(justify left bottom)
				(hide yes)
			)
		)
		(property "Val" "4u7"
			(at 248.92 64.135 90)
			(effects
				(font
					(size 1.27 1.27)
					(thickness 0.15)
				)
				(justify right)
			)
		)
		(property "Voltage" ""
			(at 276.225 44.45 0)
			(effects
				(font
					(size 1.27 1.27)
				)
				(justify left bottom)
				(hide yes)
			)
		)
		(property "Dielectric" ""
			(at 278.765 44.45 0)
			(effects
				(font
					(size 1.27 1.27)
				)
				(justify left bottom)
				(hide yes)
			)
		)
		(pin "1"
		)
		(pin "2"
		)
		(instances
			(project ""
				(path ""
					(reference "C7")
					(unit 1)
				)
			)
		)
	)
	(symbol
		(lib_id "antmicropower:GND")
		(at 221.615 67.31 0)
		(unit 1)
		(exclude_from_sim no)
		(in_bom yes)
		(on_board yes)
		(dnp no)
		(property "Reference" "#PWR0141"
			(at 221.615 73.66 0)
			(effects
				(font
					(size 1.27 1.27)
				)
				(hide yes)
			)
		)
		(property "Value" "GND"
			(at 221.615 71.12 0)
			(effects
				(font
					(size 1.27 1.27)
				)
			)
		)
		(property "Footprint" ""
			(at 221.615 67.31 0)
			(effects
				(font
					(size 1.27 1.27)
				)
				(hide yes)
			)
		)
		(property "Datasheet" ""
			(at 221.615 67.31 0)
			(effects
				(font
					(size 1.27 1.27)
				)
				(hide yes)
			)
		)
		(property "Description" ""
			(at 221.615 67.31 0)
			(effects
				(font
					(size 1.27 1.27)
				)
			)
		)
		(pin "1"
		)
		(instances
			(project ""
				(path ""
					(reference "#PWR0141")
					(unit 1)
				)
			)
		)
	)
	(symbol
		(lib_id "antmicropower:GND")
		(at 248.285 66.04 0)
		(mirror y)
		(unit 1)
		(exclude_from_sim no)
		(in_bom yes)
		(on_board yes)
		(dnp no)
		(property "Reference" "#PWR0139"
			(at 248.285 72.39 0)
			(effects
				(font
					(size 1.27 1.27)
				)
				(hide yes)
			)
		)
		(property "Value" "GND"
			(at 248.285 69.85 0)
			(effects
				(font
					(size 1.27 1.27)
				)
			)
		)
		(property "Footprint" ""
			(at 248.285 66.04 0)
			(effects
				(font
					(size 1.27 1.27)
				)
				(hide yes)
			)
		)
		(property "Datasheet" ""
			(at 248.285 66.04 0)
			(effects
				(font
					(size 1.27 1.27)
				)
				(hide yes)
			)
		)
		(property "Description" ""
			(at 248.285 66.04 0)
			(effects
				(font
					(size 1.27 1.27)
				)
			)
		)
		(pin "1"
		)
		(instances
			(project ""
				(path ""
					(reference "#PWR0139")
					(unit 1)
				)
			)
		)
	)
	(symbol
		(lib_id "antmicropower:PWR_FLAG")
		(at 167.64 29.21 0)
		(unit 1)
		(exclude_from_sim no)
		(in_bom yes)
		(on_board yes)
		(dnp no)
		(property "Reference" "#FLG01"
			(at 167.64 27.305 0)
			(effects
				(font
					(size 1.27 1.27)
				)
				(hide yes)
			)
		)
		(property "Value" "PWR_FLAG"
			(at 167.64 25.4 0)
			(effects
				(font
					(size 1.27 1.27)
				)
			)
		)
		(property "Footprint" ""
			(at 167.64 29.21 0)
			(effects
				(font
					(size 1.27 1.27)
				)
				(hide yes)
			)
		)
		(property "Datasheet" ""
			(at 167.64 29.21 0)
			(effects
				(font
					(size 1.27 1.27)
				)
				(hide yes)
			)
		)
		(property "Description" ""
			(at 167.64 29.21 0)
			(effects
				(font
					(size 1.27 1.27)
				)
			)
		)
		(pin "1"
		)
		(instances
			(project ""
				(path ""
					(reference "#FLG01")
					(unit 1)
				)
			)
		)
	)
	(symbol
		(lib_id "antmicroResistors0402:R_100k_0402")
		(at 161.29 41.91 270)
		(unit 1)
		(exclude_from_sim no)
		(in_bom no)
		(on_board yes)
		(dnp yes)
		(property "Reference" "R99"
			(at 162.56 43.18 90)
			(effects
				(font
					(size 1.27 1.27)
					(thickness 0.15)
				)
				(justify left)
			)
		)
		(property "Value" "R_100k_0402"
			(at 148.59 62.23 0)
			(effects
				(font
					(size 1.27 1.27)
					(thickness 0.15)
				)
				(justify left bottom)
				(hide yes)
			)
		)
		(property "Footprint" "antmicro-footprints:R_0402_1005Metric"
			(at 146.05 62.23 0)
			(effects
				(font
					(size 1.27 1.27)
					(thickness 0.15)
				)
				(justify left bottom)
				(hide yes)
			)
		)
		(property "Datasheet" "https://www.bourns.com/docs/product-datasheets/cr.pdf"
			(at 143.51 62.23 0)
			(effects
				(font
					(size 1.27 1.27)
					(thickness 0.15)
				)
				(justify left bottom)
				(hide yes)
			)
		)
		(property "Description" ""
			(at 161.29 41.91 0)
			(effects
				(font
					(size 1.27 1.27)
				)
			)
		)
		(property "MPN" "CR0402-FX-1003GLF"
			(at 140.97 62.23 0)
			(effects
				(font
					(size 1.27 1.27)
					(thickness 0.15)
				)
				(justify left bottom)
				(hide yes)
			)
		)
		(property "Manufacturer" "Bourns"
			(at 138.43 62.23 0)
			(effects
				(font
					(size 1.27 1.27)
					(thickness 0.15)
				)
				(justify left bottom)
				(hide yes)
			)
		)
		(property "License" "Apache-2.0"
			(at 135.89 62.23 0)
			(effects
				(font
					(size 1.27 1.27)
					(thickness 0.15)
				)
				(justify left bottom)
				(hide yes)
			)
		)
		(property "Author" "Antmicro"
			(at 133.35 62.23 0)
			(effects
				(font
					(size 1.27 1.27)
					(thickness 0.15)
				)
				(justify left bottom)
				(hide yes)
			)
		)
		(property "Val" "100k"
			(at 162.56 45.72 90)
			(effects
				(font
					(size 1.27 1.27)
					(thickness 0.15)
				)
				(justify left)
			)
		)
		(property "Tolerance" "1%"
			(at 151.13 62.23 0)
			(effects
				(font
					(size 1.27 1.27)
				)
				(justify left bottom)
				(hide yes)
			)
		)
		(pin "1"
		)
		(pin "2"
		)
		(instances
			(project ""
				(path ""
					(reference "R99")
					(unit 1)
				)
			)
		)
	)
	(symbol
		(lib_id "antmicroEdgeConnectors:PCB-Edge_SODIMM_2x131_LPDDR5_Testbed")
		(at 85.09 104.14 0)
		(unit 2)
		(exclude_from_sim no)
		(in_bom no)
		(on_board yes)
		(dnp no)
		(property "Reference" "J1"
			(at 102.87 93.98 0)
			(effects
				(font
					(size 1.27 1.27)
				)
			)
		)
		(property "Value" "PCB-Edge_SODIMM_2x131_LPDDR5_Testbed"
			(at 102.87 97.79 0)
			(effects
				(font
					(size 1.27 1.27)
				)
			)
		)
		(property "Footprint" "antmicro-footprints:PCB-Edge_SODIMM_2x131_DDR5"
			(at 137.16 116.84 0)
			(effects
				(font
					(size 1.27 1.27)
				)
				(justify left bottom)
				(hide yes)
			)
		)
		(property "Datasheet" "https://cdn.amphenol-cs.com/media/wysiwyg/files/drawing/10162416.pdf"
			(at 137.16 114.3 0)
			(effects
				(font
					(size 1.27 1.27)
				)
				(justify left bottom)
				(hide yes)
			)
		)
		(property "Description" "Memory Card Connector, LPDDR5 SO-DIMM, PCB Edge"
			(at 137.16 124.46 0)
			(effects
				(font
					(size 1.27 1.27)
				)
				(justify left bottom)
				(hide yes)
			)
		)
		(property "MPN" ""
			(at 137.16 111.76 0)
			(effects
				(font
					(size 1.27 1.27)
				)
				(justify left bottom)
			)
		)
		(property "Manufacturer" ""
			(at 137.16 109.22 0)
			(effects
				(font
					(size 1.27 1.27)
				)
				(justify left bottom)
				(hide yes)
			)
		)
		(property "Author" "Antmicro"
			(at 137.16 121.92 0)
			(effects
				(font
					(size 1.27 1.27)
				)
				(justify left bottom)
				(hide yes)
			)
		)
		(property "License" "Apache-2.0"
			(at 137.16 119.38 0)
			(effects
				(font
					(size 1.27 1.27)
				)
				(justify left bottom)
				(hide yes)
			)
		)
		(pin "1"
		)
		(pin "10"
		)
		(pin "101"
		)
		(pin "104"
		)
		(pin "105"
		)
		(pin "108"
		)
		(pin "111"
		)
		(pin "112"
		)
		(pin "117"
		)
		(pin "118"
		)
		(pin "123"
		)
		(pin "124"
		)
		(pin "128"
		)
		(pin "129"
		)
		(pin "13"
		)
		(pin "130"
		)
		(pin "135"
		)
		(pin "136"
		)
		(pin "14"
		)
		(pin "141"
		)
		(pin "142"
		)
		(pin "143"
		)
		(pin "147"
		)
		(pin "148"
		)
		(pin "153"
		)
		(pin "154"
		)
		(pin "159"
		)
		(pin "160"
		)
		(pin "163"
		)
		(pin "166"
		)
		(pin "167"
		)
		(pin "17"
		)
		(pin "170"
		)
		(pin "173"
		)
		(pin "174"
		)
		(pin "177"
		)
		(pin "178"
		)
		(pin "18"
		)
		(pin "181"
		)
		(pin "182"
		)
		(pin "185"
		)
		(pin "186"
		)
		(pin "189"
		)
		(pin "192"
		)
		(pin "193"
		)
		(pin "196"
		)
		(pin "197"
		)
		(pin "2"
		)
		(pin "200"
		)
		(pin "201"
		)
		(pin "204"
		)
		(pin "205"
		)
		(pin "208"
		)
		(pin "21"
		)
		(pin "211"
		)
		(pin "212"
		)
		(pin "215"
		)
		(pin "216"
		)
		(pin "219"
		)
		(pin "220"
		)
		(pin "223"
		)
		(pin "224"
		)
		(pin "227"
		)
		(pin "228"
		)
		(pin "231"
		)
		(pin "234"
		)
		(pin "235"
		)
		(pin "238"
		)
		(pin "239"
		)
		(pin "24"
		)
		(pin "242"
		)
		(pin "243"
		)
		(pin "246"
		)
		(pin "247"
		)
		(pin "25"
		)
		(pin "250"
		)
		(pin "253"
		)
		(pin "254"
		)
		(pin "257"
		)
		(pin "258"
		)
		(pin "261"
		)
		(pin "262"
		)
		(pin "28"
		)
		(pin "29"
		)
		(pin "3"
		)
		(pin "32"
		)
		(pin "33"
		)
		(pin "36"
		)
		(pin "37"
		)
		(pin "4"
		)
		(pin "40"
		)
		(pin "43"
		)
		(pin "44"
		)
		(pin "47"
		)
		(pin "48"
		)
		(pin "5"
		)
		(pin "51"
		)
		(pin "52"
		)
		(pin "55"
		)
		(pin "56"
		)
		(pin "59"
		)
		(pin "6"
		)
		(pin "60"
		)
		(pin "63"
		)
		(pin "66"
		)
		(pin "67"
		)
		(pin "7"
		)
		(pin "70"
		)
		(pin "71"
		)
		(pin "74"
		)
		(pin "75"
		)
		(pin "78"
		)
		(pin "79"
		)
		(pin "8"
		)
		(pin "82"
		)
		(pin "85"
		)
		(pin "86"
		)
		(pin "89"
		)
		(pin "9"
		)
		(pin "90"
		)
		(pin "93"
		)
		(pin "94"
		)
		(pin "97"
		)
		(pin "98"
		)
		(pin "100"
		)
		(pin "102"
		)
		(pin "103"
		)
		(pin "106"
		)
		(pin "107"
		)
		(pin "109"
		)
		(pin "11"
		)
		(pin "110"
		)
		(pin "113"
		)
		(pin "114"
		)
		(pin "115"
		)
		(pin "116"
		)
		(pin "119"
		)
		(pin "12"
		)
		(pin "120"
		)
		(pin "121"
		)
		(pin "122"
		)
		(pin "125"
		)
		(pin "126"
		)
		(pin "127"
		)
		(pin "131"
		)
		(pin "132"
		)
		(pin "133"
		)
		(pin "134"
		)
		(pin "15"
		)
		(pin "16"
		)
		(pin "19"
		)
		(pin "20"
		)
		(pin "22"
		)
		(pin "23"
		)
		(pin "26"
		)
		(pin "27"
		)
		(pin "30"
		)
		(pin "31"
		)
		(pin "34"
		)
		(pin "35"
		)
		(pin "38"
		)
		(pin "39"
		)
		(pin "41"
		)
		(pin "42"
		)
		(pin "45"
		)
		(pin "46"
		)
		(pin "49"
		)
		(pin "50"
		)
		(pin "53"
		)
		(pin "54"
		)
		(pin "57"
		)
		(pin "58"
		)
		(pin "61"
		)
		(pin "62"
		)
		(pin "64"
		)
		(pin "65"
		)
		(pin "68"
		)
		(pin "69"
		)
		(pin "72"
		)
		(pin "73"
		)
		(pin "76"
		)
		(pin "77"
		)
		(pin "80"
		)
		(pin "81"
		)
		(pin "83"
		)
		(pin "84"
		)
		(pin "87"
		)
		(pin "88"
		)
		(pin "91"
		)
		(pin "92"
		)
		(pin "95"
		)
		(pin "96"
		)
		(pin "99"
		)
		(pin "137"
		)
		(pin "138"
		)
		(pin "139"
		)
		(pin "140"
		)
		(pin "144"
		)
		(pin "145"
		)
		(pin "146"
		)
		(pin "149"
		)
		(pin "150"
		)
		(pin "151"
		)
		(pin "152"
		)
		(pin "155"
		)
		(pin "156"
		)
		(pin "157"
		)
		(pin "158"
		)
		(pin "161"
		)
		(pin "162"
		)
		(pin "164"
		)
		(pin "165"
		)
		(pin "168"
		)
		(pin "169"
		)
		(pin "171"
		)
		(pin "172"
		)
		(pin "175"
		)
		(pin "176"
		)
		(pin "179"
		)
		(pin "180"
		)
		(pin "183"
		)
		(pin "184"
		)
		(pin "187"
		)
		(pin "188"
		)
		(pin "190"
		)
		(pin "191"
		)
		(pin "194"
		)
		(pin "195"
		)
		(pin "198"
		)
		(pin "199"
		)
		(pin "202"
		)
		(pin "203"
		)
		(pin "206"
		)
		(pin "207"
		)
		(pin "209"
		)
		(pin "210"
		)
		(pin "213"
		)
		(pin "214"
		)
		(pin "217"
		)
		(pin "218"
		)
		(pin "221"
		)
		(pin "222"
		)
		(pin "225"
		)
		(pin "226"
		)
		(pin "229"
		)
		(pin "230"
		)
		(pin "232"
		)
		(pin "233"
		)
		(pin "236"
		)
		(pin "237"
		)
		(pin "240"
		)
		(pin "241"
		)
		(pin "244"
		)
		(pin "245"
		)
		(pin "248"
		)
		(pin "249"
		)
		(pin "251"
		)
		(pin "252"
		)
		(pin "255"
		)
		(pin "256"
		)
		(pin "259"
		)
		(pin "260"
		)
		(instances
			(project ""
				(path ""
					(reference "J1")
					(unit 2)
				)
			)
		)
	)
	(symbol
		(lib_id "lpddr5-testbed:Edge_Conn_Bus_DDR5_SODIMM_1xDetectPin")
		(at 237.49 104.14 0)
		(unit 3)
		(exclude_from_sim no)
		(in_bom yes)
		(on_board yes)
		(dnp no)
		(property "Reference" "J1"
			(at 255.27 96.52 0)
			(effects
				(font
					(size 1.27 1.27)
				)
			)
		)
		(property "Value" "PCB-Edge_SODIMM_2x131_LPDDR5_Testbed"
			(at 255.27 99.06 0)
			(effects
				(font
					(size 1.27 1.27)
				)
			)
		)
		(property "Footprint" "lpddr5-testbed-footprints:Edge_Conn_Bus_DDR5_SODIMM"
			(at 289.56 116.84 0)
			(effects
				(font
					(size 1.27 1.27)
				)
				(justify left bottom)
				(hide yes)
			)
		)
		(property "Datasheet" "https://cdn.amphenol-cs.com/media/wysiwyg/files/drawing/10162416.pdf"
			(at 289.56 114.3 0)
			(effects
				(font
					(size 1.27 1.27)
				)
				(justify left bottom)
				(hide yes)
			)
		)
		(property "Description" ""
			(at 237.49 104.14 0)
			(effects
				(font
					(size 1.27 1.27)
				)
			)
		)
		(property "MPN" ""
			(at 289.56 111.76 0)
			(effects
				(font
					(size 1.27 1.27)
				)
				(justify left bottom)
				(hide yes)
			)
		)
		(property "Manufacturer" ""
			(at 289.56 109.22 0)
			(effects
				(font
					(size 1.27 1.27)
				)
				(justify left bottom)
				(hide yes)
			)
		)
		(property "Author" "Antmicro"
			(at 289.56 121.92 0)
			(effects
				(font
					(size 1.27 1.27)
				)
				(justify left bottom)
				(hide yes)
			)
		)
		(property "License" "Apache-2.0"
			(at 289.56 119.38 0)
			(effects
				(font
					(size 1.27 1.27)
				)
				(justify left bottom)
				(hide yes)
			)
		)
		(pin "1"
		)
		(pin "10"
		)
		(pin "101"
		)
		(pin "104"
		)
		(pin "105"
		)
		(pin "108"
		)
		(pin "111"
		)
		(pin "112"
		)
		(pin "117"
		)
		(pin "118"
		)
		(pin "123"
		)
		(pin "124"
		)
		(pin "128"
		)
		(pin "129"
		)
		(pin "13"
		)
		(pin "130"
		)
		(pin "135"
		)
		(pin "136"
		)
		(pin "14"
		)
		(pin "141"
		)
		(pin "142"
		)
		(pin "143"
		)
		(pin "147"
		)
		(pin "148"
		)
		(pin "153"
		)
		(pin "154"
		)
		(pin "159"
		)
		(pin "160"
		)
		(pin "163"
		)
		(pin "166"
		)
		(pin "167"
		)
		(pin "17"
		)
		(pin "170"
		)
		(pin "173"
		)
		(pin "174"
		)
		(pin "177"
		)
		(pin "178"
		)
		(pin "18"
		)
		(pin "181"
		)
		(pin "182"
		)
		(pin "185"
		)
		(pin "186"
		)
		(pin "189"
		)
		(pin "192"
		)
		(pin "193"
		)
		(pin "196"
		)
		(pin "197"
		)
		(pin "2"
		)
		(pin "200"
		)
		(pin "201"
		)
		(pin "204"
		)
		(pin "205"
		)
		(pin "208"
		)
		(pin "21"
		)
		(pin "211"
		)
		(pin "212"
		)
		(pin "215"
		)
		(pin "216"
		)
		(pin "219"
		)
		(pin "220"
		)
		(pin "223"
		)
		(pin "224"
		)
		(pin "227"
		)
		(pin "228"
		)
		(pin "231"
		)
		(pin "234"
		)
		(pin "235"
		)
		(pin "238"
		)
		(pin "239"
		)
		(pin "24"
		)
		(pin "242"
		)
		(pin "243"
		)
		(pin "246"
		)
		(pin "247"
		)
		(pin "25"
		)
		(pin "250"
		)
		(pin "253"
		)
		(pin "254"
		)
		(pin "257"
		)
		(pin "258"
		)
		(pin "261"
		)
		(pin "262"
		)
		(pin "28"
		)
		(pin "29"
		)
		(pin "3"
		)
		(pin "32"
		)
		(pin "33"
		)
		(pin "36"
		)
		(pin "37"
		)
		(pin "4"
		)
		(pin "40"
		)
		(pin "43"
		)
		(pin "44"
		)
		(pin "47"
		)
		(pin "48"
		)
		(pin "5"
		)
		(pin "51"
		)
		(pin "52"
		)
		(pin "55"
		)
		(pin "56"
		)
		(pin "59"
		)
		(pin "6"
		)
		(pin "60"
		)
		(pin "63"
		)
		(pin "66"
		)
		(pin "67"
		)
		(pin "7"
		)
		(pin "70"
		)
		(pin "71"
		)
		(pin "74"
		)
		(pin "75"
		)
		(pin "78"
		)
		(pin "79"
		)
		(pin "8"
		)
		(pin "82"
		)
		(pin "85"
		)
		(pin "86"
		)
		(pin "89"
		)
		(pin "9"
		)
		(pin "90"
		)
		(pin "93"
		)
		(pin "94"
		)
		(pin "97"
		)
		(pin "98"
		)
		(pin "100"
		)
		(pin "102"
		)
		(pin "103"
		)
		(pin "106"
		)
		(pin "107"
		)
		(pin "109"
		)
		(pin "11"
		)
		(pin "110"
		)
		(pin "113"
		)
		(pin "114"
		)
		(pin "115"
		)
		(pin "116"
		)
		(pin "119"
		)
		(pin "12"
		)
		(pin "120"
		)
		(pin "121"
		)
		(pin "122"
		)
		(pin "125"
		)
		(pin "126"
		)
		(pin "127"
		)
		(pin "131"
		)
		(pin "132"
		)
		(pin "133"
		)
		(pin "134"
		)
		(pin "15"
		)
		(pin "16"
		)
		(pin "19"
		)
		(pin "20"
		)
		(pin "22"
		)
		(pin "23"
		)
		(pin "26"
		)
		(pin "27"
		)
		(pin "30"
		)
		(pin "31"
		)
		(pin "34"
		)
		(pin "35"
		)
		(pin "38"
		)
		(pin "39"
		)
		(pin "41"
		)
		(pin "42"
		)
		(pin "45"
		)
		(pin "46"
		)
		(pin "49"
		)
		(pin "50"
		)
		(pin "53"
		)
		(pin "54"
		)
		(pin "57"
		)
		(pin "58"
		)
		(pin "61"
		)
		(pin "62"
		)
		(pin "64"
		)
		(pin "65"
		)
		(pin "68"
		)
		(pin "69"
		)
		(pin "72"
		)
		(pin "73"
		)
		(pin "76"
		)
		(pin "77"
		)
		(pin "80"
		)
		(pin "81"
		)
		(pin "83"
		)
		(pin "84"
		)
		(pin "87"
		)
		(pin "88"
		)
		(pin "91"
		)
		(pin "92"
		)
		(pin "95"
		)
		(pin "96"
		)
		(pin "99"
		)
		(pin "137"
		)
		(pin "138"
		)
		(pin "139"
		)
		(pin "140"
		)
		(pin "144"
		)
		(pin "145"
		)
		(pin "146"
		)
		(pin "149"
		)
		(pin "150"
		)
		(pin "151"
		)
		(pin "152"
		)
		(pin "155"
		)
		(pin "156"
		)
		(pin "157"
		)
		(pin "158"
		)
		(pin "161"
		)
		(pin "162"
		)
		(pin "164"
		)
		(pin "165"
		)
		(pin "168"
		)
		(pin "169"
		)
		(pin "171"
		)
		(pin "172"
		)
		(pin "175"
		)
		(pin "176"
		)
		(pin "179"
		)
		(pin "180"
		)
		(pin "183"
		)
		(pin "184"
		)
		(pin "187"
		)
		(pin "188"
		)
		(pin "190"
		)
		(pin "191"
		)
		(pin "194"
		)
		(pin "195"
		)
		(pin "198"
		)
		(pin "199"
		)
		(pin "202"
		)
		(pin "203"
		)
		(pin "206"
		)
		(pin "207"
		)
		(pin "209"
		)
		(pin "210"
		)
		(pin "213"
		)
		(pin "214"
		)
		(pin "217"
		)
		(pin "218"
		)
		(pin "221"
		)
		(pin "222"
		)
		(pin "225"
		)
		(pin "226"
		)
		(pin "229"
		)
		(pin "230"
		)
		(pin "232"
		)
		(pin "233"
		)
		(pin "236"
		)
		(pin "237"
		)
		(pin "240"
		)
		(pin "241"
		)
		(pin "244"
		)
		(pin "245"
		)
		(pin "248"
		)
		(pin "249"
		)
		(pin "251"
		)
		(pin "252"
		)
		(pin "255"
		)
		(pin "256"
		)
		(pin "259"
		)
		(pin "260"
		)
		(instances
			(project ""
				(path ""
					(reference "J1")
					(unit 3)
				)
			)
		)
	)
	(symbol
		(lib_id "antmicroMemory:AT24CS01_SOT23")
		(at 222.885 60.96 0)
		(unit 1)
		(exclude_from_sim no)
		(in_bom yes)
		(on_board yes)
		(dnp no)
		(fields_autoplaced yes)
		(property "Reference" "U7"
			(at 233.045 53.34 0)
			(effects
				(font
					(size 1.27 1.27)
					(thickness 0.15)
				)
			)
		)
		(property "Value" "AT24CS01_SOT23"
			(at 233.045 55.88 0)
			(effects
				(font
					(size 1.27 1.27)
					(thickness 0.15)
				)
			)
		)
		(property "Footprint" "antmicro-footprints:SOT-23-5"
			(at 258.445 68.58 0)
			(effects
				(font
					(size 1.27 1.27)
					(thickness 0.15)
				)
				(justify left bottom)
				(hide yes)
			)
		)
		(property "Datasheet" "http://ww1.microchip.com/downloads/en/devicedoc/Atmel-8815-SEEPROM-AT24CS01-02-Datasheet.pdf"
			(at 258.445 71.12 0)
			(effects
				(font
					(size 1.27 1.27)
					(thickness 0.15)
				)
				(justify left bottom)
				(hide yes)
			)
		)
		(property "Description" ""
			(at 222.885 60.96 0)
			(effects
				(font
					(size 1.27 1.27)
				)
			)
		)
		(property "Manufacturer" "Atmel"
			(at 258.445 73.66 0)
			(effects
				(font
					(size 1.27 1.27)
					(thickness 0.15)
				)
				(justify left bottom)
				(hide yes)
			)
		)
		(property "MPN" "AT24CS01-ST"
			(at 258.445 76.2 0)
			(effects
				(font
					(size 1.27 1.27)
					(thickness 0.15)
				)
				(justify left bottom)
				(hide yes)
			)
		)
		(property "Author" "Antmicro"
			(at 258.445 78.74 0)
			(effects
				(font
					(size 1.27 1.27)
					(thickness 0.15)
				)
				(justify left bottom)
				(hide yes)
			)
		)
		(property "License" "Apache-2.0"
			(at 258.445 81.28 0)
			(effects
				(font
					(size 1.27 1.27)
					(thickness 0.15)
				)
				(justify left bottom)
				(hide yes)
			)
		)
		(pin "1"
		)
		(pin "2"
		)
		(pin "3"
		)
		(pin "4"
		)
		(pin "5"
		)
		(instances
			(project ""
				(path ""
					(reference "U7")
					(unit 1)
				)
			)
		)
	)
)
